G04 ================== begin FILE IDENTIFICATION RECORD ==================*
G04 Layout Name:  D:/<user>/Wistron_project/16316-1/gbr-0621/16316-1.brd*
G04 Film Name:    DP_REF_L8*
G04 File Format:  Gerber RS274X*
G04 File Origin:  Cadence Allegro 16.5-S056*
G04 Origin Date:  Wed Jun 21 09:32:38 2017*
G04 *
G04 Layer:  BOARD GEOMETRY/DP_REF_L8_TBL*
G04 Layer:  BOARD GEOMETRY/DP_REF_L8_BOTTOM*
G04 Layer:  BOARD GEOMETRY/PANEL_OUTLINE*
G04 *
G04 Offset:    (0.00 0.00)*
G04 Mirror:    No*
G04 Mode:      Positive*
G04 Rotation:  0*
G04 FullContactRelief:  No*
G04 UndefLineWidth:     6.00*
G04 ================== end FILE IDENTIFICATION RECORD ====================*
%FSLAX35Y35*MOIN*%
%IR0*IPPOS*OFA0.00000B0.00000*MIA0B0*SFA1.00000B1.00000*%
%ADD10C,.02*%
%ADD11C,.006*%
%ADD12C,.0049*%
%ADD13C,.00575*%
G75*
%LPD*%
G75*
G54D10*
G01X877071Y397916D02*
X1629571D01*
G01X877071Y363266D02*
X1629571D01*
G01X877071Y536516D02*
Y363266D01*
G01Y467216D02*
X1629571D01*
G01X877071Y432566D02*
X1629571D01*
G01X877071Y536516D02*
X1629571D01*
G01X877071Y501866D02*
X1629571D01*
G01X1052071Y536516D02*
Y363266D01*
G01X1314571Y536516D02*
Y363266D01*
G01X1419571Y536516D02*
Y363266D01*
G01X1629571Y536516D02*
Y363266D01*
G54D11*
G01X6250Y-135162D02*
Y-152662D01*
G01X1228Y-135162D02*
X11272D01*
G01X20038Y-152662D02*
Y-135162D01*
G01Y-143620D02*
X21130Y-142162D01*
X22222Y-141287D01*
X23968Y-140996D01*
X25278Y-141287D01*
X26807Y-142454D01*
X27462Y-144204D01*
Y-152662D01*
G01X41250Y-140996D02*
Y-152662D01*
G01Y-136329D02*
X40813Y-136037D01*
Y-135454D01*
X41250Y-135162D01*
X41687Y-135454D01*
Y-136037D01*
X41250Y-136329D01*
G01X55475Y-150621D02*
X56567Y-151787D01*
X58095Y-152662D01*
X59405D01*
X60715Y-152079D01*
X61588Y-151204D01*
X62025Y-150038D01*
X61807Y-148287D01*
X60933Y-147412D01*
X57003Y-145662D01*
X56130Y-143620D01*
X56567Y-142162D01*
X57440Y-141287D01*
X58750Y-140996D01*
X60060Y-141287D01*
X61370Y-142162D01*
G01X90693Y-157037D02*
X92222Y-158204D01*
X93968Y-158495D01*
X95496Y-158204D01*
X96807Y-156746D01*
X97680Y-154704D01*
Y-140996D01*
G01Y-143329D02*
X96807Y-142162D01*
X95496Y-141287D01*
X93968Y-140996D01*
X92222Y-141579D01*
X91130Y-142745D01*
X90256Y-144787D01*
X89820Y-146829D01*
X90038Y-148579D01*
X90912Y-150621D01*
X92222Y-152079D01*
X93968Y-152662D01*
X95278Y-152370D01*
X96807Y-151204D01*
X97680Y-150038D01*
G01X107975Y-144787D02*
X114962D01*
X114307Y-142745D01*
X113215Y-141579D01*
X111687Y-140996D01*
X110158Y-141287D01*
X108848Y-142162D01*
X107975Y-144204D01*
X107538Y-145954D01*
Y-147704D01*
X107975Y-149454D01*
X109067Y-151204D01*
X110377Y-152370D01*
X111905Y-152662D01*
X113433Y-152079D01*
X114962Y-150329D01*
G01X125693Y-152662D02*
Y-140996D01*
G01Y-143329D02*
X126785Y-142162D01*
X127877Y-141287D01*
X129405Y-140996D01*
X130496Y-141287D01*
X131807Y-142162D01*
G01X142320Y-152662D02*
Y-135162D01*
G01Y-143912D02*
X143412Y-142162D01*
X144722Y-141287D01*
X146032Y-140996D01*
X147996Y-141579D01*
X149307Y-142745D01*
X150180Y-144787D01*
Y-147120D01*
X149743Y-149454D01*
X148870Y-151204D01*
X147342Y-152370D01*
X146032Y-152662D01*
X144722Y-152370D01*
X143412Y-151496D01*
X142320Y-150038D01*
G01X160475Y-144787D02*
X167462D01*
X166807Y-142745D01*
X165715Y-141579D01*
X164187Y-140996D01*
X162658Y-141287D01*
X161348Y-142162D01*
X160475Y-144204D01*
X160038Y-145954D01*
Y-147704D01*
X160475Y-149454D01*
X161567Y-151204D01*
X162877Y-152370D01*
X164405Y-152662D01*
X165933Y-152079D01*
X167462Y-150329D01*
G01X178193Y-152662D02*
Y-140996D01*
G01Y-143329D02*
X179285Y-142162D01*
X180377Y-141287D01*
X181905Y-140996D01*
X182996Y-141287D01*
X184307Y-142162D01*
G01X216250Y-140996D02*
Y-152662D01*
G01Y-136329D02*
X215813Y-136037D01*
Y-135454D01*
X216250Y-135162D01*
X216687Y-135454D01*
Y-136037D01*
X216250Y-136329D01*
G01X230475Y-150621D02*
X231567Y-151787D01*
X233095Y-152662D01*
X234405D01*
X235715Y-152079D01*
X236588Y-151204D01*
X237025Y-150038D01*
X236807Y-148287D01*
X235933Y-147412D01*
X232003Y-145662D01*
X231130Y-143620D01*
X231567Y-142162D01*
X232440Y-141287D01*
X233750Y-140996D01*
X235060Y-141287D01*
X236370Y-142162D01*
G01X265256Y-157037D02*
X266785Y-158204D01*
X268095Y-158495D01*
X269842Y-157912D01*
X271152Y-156454D01*
X271807Y-153828D01*
Y-140996D01*
G01Y-136329D02*
X271370Y-136037D01*
Y-135454D01*
X271807Y-135162D01*
X272243Y-135454D01*
Y-136037D01*
X271807Y-136329D01*
G01X282538Y-140996D02*
Y-149162D01*
X283412Y-151204D01*
X284722Y-152370D01*
X286250Y-152662D01*
X287778Y-152370D01*
X289088Y-151204D01*
X289962Y-149162D01*
G01Y-152662D02*
Y-140996D01*
G01X300475Y-150621D02*
X301567Y-151787D01*
X303095Y-152662D01*
X304405D01*
X305715Y-152079D01*
X306588Y-151204D01*
X307025Y-150038D01*
X306807Y-148287D01*
X305933Y-147412D01*
X302003Y-145662D01*
X301130Y-143620D01*
X301567Y-142162D01*
X302440Y-141287D01*
X303750Y-140996D01*
X305060Y-141287D01*
X306370Y-142162D01*
G01X321250Y-135162D02*
Y-152662D01*
G01X318193Y-140996D02*
X324307D01*
G01X354940Y-152662D02*
Y-137787D01*
X355377Y-136329D01*
X356250Y-135454D01*
X357560Y-135162D01*
X358870Y-135745D01*
X359525Y-137204D01*
G01X356905Y-142162D02*
X352538D01*
G01X373750Y-152662D02*
X372440Y-152370D01*
X371130Y-151204D01*
X370256Y-149162D01*
X369820Y-146829D01*
X370256Y-144495D01*
X371130Y-142454D01*
X372440Y-141287D01*
X373750Y-140996D01*
X375060Y-141287D01*
X376370Y-142454D01*
X377243Y-144495D01*
X377462Y-146829D01*
X377243Y-149162D01*
X376370Y-151204D01*
X375060Y-152370D01*
X373750Y-152662D01*
G01X388193D02*
Y-140996D01*
G01Y-143329D02*
X389285Y-142162D01*
X390377Y-141287D01*
X391905Y-140996D01*
X392996Y-141287D01*
X394307Y-142162D01*
G01X421665Y-157912D02*
X422975Y-158495D01*
X424722Y-157912D01*
X425813Y-156746D01*
X426687Y-155287D01*
X427996Y-150621D01*
X430835Y-140996D01*
G01X423848D02*
X427996Y-150621D01*
G01X443750Y-152662D02*
X442440Y-152370D01*
X441130Y-151204D01*
X440256Y-149162D01*
X439820Y-146829D01*
X440256Y-144495D01*
X441130Y-142454D01*
X442440Y-141287D01*
X443750Y-140996D01*
X445060Y-141287D01*
X446370Y-142454D01*
X447243Y-144495D01*
X447462Y-146829D01*
X447243Y-149162D01*
X446370Y-151204D01*
X445060Y-152370D01*
X443750Y-152662D01*
G01X457538Y-140996D02*
Y-149162D01*
X458412Y-151204D01*
X459722Y-152370D01*
X461250Y-152662D01*
X462778Y-152370D01*
X464088Y-151204D01*
X464962Y-149162D01*
G01Y-152662D02*
Y-140996D01*
G01X475693Y-152662D02*
Y-140996D01*
G01Y-143329D02*
X476785Y-142162D01*
X477877Y-141287D01*
X479405Y-140996D01*
X480496Y-141287D01*
X481807Y-142162D01*
G01X510693Y-152662D02*
Y-140996D01*
G01Y-143329D02*
X511785Y-142162D01*
X512877Y-141287D01*
X514405Y-140996D01*
X515496Y-141287D01*
X516807Y-142162D01*
G01X527975Y-144787D02*
X534962D01*
X534307Y-142745D01*
X533215Y-141579D01*
X531687Y-140996D01*
X530158Y-141287D01*
X528848Y-142162D01*
X527975Y-144204D01*
X527538Y-145954D01*
Y-147704D01*
X527975Y-149454D01*
X529067Y-151204D01*
X530377Y-152370D01*
X531905Y-152662D01*
X533433Y-152079D01*
X534962Y-150329D01*
G01X547440Y-152662D02*
Y-137787D01*
X547877Y-136329D01*
X548750Y-135454D01*
X550060Y-135162D01*
X551370Y-135745D01*
X552025Y-137204D01*
G01X549405Y-142162D02*
X545038D01*
G01X562975Y-144787D02*
X569962D01*
X569307Y-142745D01*
X568215Y-141579D01*
X566687Y-140996D01*
X565158Y-141287D01*
X563848Y-142162D01*
X562975Y-144204D01*
X562538Y-145954D01*
Y-147704D01*
X562975Y-149454D01*
X564067Y-151204D01*
X565377Y-152370D01*
X566905Y-152662D01*
X568433Y-152079D01*
X569962Y-150329D01*
G01X580693Y-152662D02*
Y-140996D01*
G01Y-143329D02*
X581785Y-142162D01*
X582877Y-141287D01*
X584405Y-140996D01*
X585496Y-141287D01*
X586807Y-142162D01*
G01X597975Y-144787D02*
X604962D01*
X604307Y-142745D01*
X603215Y-141579D01*
X601687Y-140996D01*
X600158Y-141287D01*
X598848Y-142162D01*
X597975Y-144204D01*
X597538Y-145954D01*
Y-147704D01*
X597975Y-149454D01*
X599067Y-151204D01*
X600377Y-152370D01*
X601905Y-152662D01*
X603433Y-152079D01*
X604962Y-150329D01*
G01X615038Y-152662D02*
Y-140996D01*
G01Y-143912D02*
X615912Y-142454D01*
X617222Y-141287D01*
X618968Y-140996D01*
X620496Y-141287D01*
X621807Y-142454D01*
X622462Y-144495D01*
Y-152662D01*
G01X639743Y-142454D02*
X638215Y-141287D01*
X636905Y-140996D01*
X635158Y-141579D01*
X633848Y-142745D01*
X632975Y-144787D01*
X632756Y-146829D01*
X632975Y-148871D01*
X633848Y-150621D01*
X635158Y-152079D01*
X636905Y-152662D01*
X638433Y-152079D01*
X639743Y-150912D01*
G01X650475Y-144787D02*
X657462D01*
X656807Y-142745D01*
X655715Y-141579D01*
X654187Y-140996D01*
X652658Y-141287D01*
X651348Y-142162D01*
X650475Y-144204D01*
X650038Y-145954D01*
Y-147704D01*
X650475Y-149454D01*
X651567Y-151204D01*
X652877Y-152370D01*
X654405Y-152662D01*
X655933Y-152079D01*
X657462Y-150329D01*
G01X688750Y-135162D02*
Y-152662D01*
G01X685693Y-140996D02*
X691807D01*
G01X706250Y-152662D02*
X704940Y-152370D01*
X703630Y-151204D01*
X702756Y-149162D01*
X702320Y-146829D01*
X702756Y-144495D01*
X703630Y-142454D01*
X704940Y-141287D01*
X706250Y-140996D01*
X707560Y-141287D01*
X708870Y-142454D01*
X709743Y-144495D01*
X709962Y-146829D01*
X709743Y-149162D01*
X708870Y-151204D01*
X707560Y-152370D01*
X706250Y-152662D01*
G01X739940D02*
Y-137787D01*
X740377Y-136329D01*
X741250Y-135454D01*
X742560Y-135162D01*
X743870Y-135745D01*
X744525Y-137204D01*
G01X741905Y-142162D02*
X737538D01*
G01X758750Y-140996D02*
Y-152662D01*
G01Y-136329D02*
X758313Y-136037D01*
Y-135454D01*
X758750Y-135162D01*
X759187Y-135454D01*
Y-136037D01*
X758750Y-136329D01*
G01X772538Y-152662D02*
Y-140996D01*
G01Y-143912D02*
X773412Y-142454D01*
X774722Y-141287D01*
X776468Y-140996D01*
X777996Y-141287D01*
X779307Y-142454D01*
X779962Y-144495D01*
Y-152662D01*
G01X797680Y-135162D02*
Y-152662D01*
G01Y-150038D02*
X796807Y-151496D01*
X795496Y-152370D01*
X793968Y-152662D01*
X792222Y-152079D01*
X790912Y-150621D01*
X790038Y-148871D01*
X789820Y-146829D01*
X790038Y-144787D01*
X790912Y-143037D01*
X792222Y-141579D01*
X793968Y-140996D01*
X795496Y-141287D01*
X796588Y-141871D01*
X797680Y-143037D01*
G01X828750Y-135162D02*
Y-152662D01*
G01X825693Y-140996D02*
X831807D01*
G01X842538Y-152662D02*
Y-135162D01*
G01Y-143620D02*
X843630Y-142162D01*
X844722Y-141287D01*
X846468Y-140996D01*
X847778Y-141287D01*
X849307Y-142454D01*
X849962Y-144204D01*
Y-152662D01*
G01X860475Y-144787D02*
X867462D01*
X866807Y-142745D01*
X865715Y-141579D01*
X864187Y-140996D01*
X862658Y-141287D01*
X861348Y-142162D01*
X860475Y-144204D01*
X860038Y-145954D01*
Y-147704D01*
X860475Y-149454D01*
X861567Y-151204D01*
X862877Y-152370D01*
X864405Y-152662D01*
X865933Y-152079D01*
X867462Y-150329D01*
G01X893947Y-152662D02*
Y-135162D01*
X898313D01*
X900060Y-136037D01*
X901370Y-137204D01*
X902462Y-138953D01*
X903335Y-140996D01*
X903553Y-143912D01*
X903335Y-146829D01*
X902462Y-148871D01*
X901370Y-150621D01*
X900060Y-151787D01*
X898313Y-152662D01*
X893947D01*
G01X911883D02*
Y-135162D01*
X917123D01*
X918870Y-136037D01*
X920180Y-138079D01*
X920617Y-140412D01*
X920180Y-142745D01*
X919088Y-144495D01*
X917123Y-145371D01*
X911883D01*
G01X951250Y-140996D02*
Y-152662D01*
G01Y-136329D02*
X950813Y-136037D01*
Y-135454D01*
X951250Y-135162D01*
X951687Y-135454D01*
Y-136037D01*
X951250Y-136329D01*
G01X962200Y-152662D02*
Y-140996D01*
G01Y-144204D02*
X962855Y-142745D01*
X963947Y-141579D01*
X965475Y-140996D01*
X967003Y-141579D01*
X968095Y-142745D01*
X968750Y-144204D01*
Y-152662D01*
G01Y-144204D02*
X969405Y-142745D01*
X970496Y-141579D01*
X972025Y-140996D01*
X973553Y-141579D01*
X974645Y-142745D01*
X975300Y-144495D01*
Y-152662D01*
G01X982320Y-158495D02*
Y-140996D01*
G01Y-143620D02*
X983412Y-142162D01*
X984503Y-141287D01*
X986250Y-140996D01*
X987778Y-141287D01*
X989307Y-142745D01*
X989962Y-144787D01*
X990180Y-146829D01*
X989962Y-148871D01*
X989307Y-150912D01*
X987996Y-152079D01*
X986250Y-152662D01*
X984722Y-152370D01*
X983193Y-151496D01*
X982320Y-150329D01*
G01X1000475Y-144787D02*
X1007462D01*
X1006807Y-142745D01*
X1005715Y-141579D01*
X1004187Y-140996D01*
X1002658Y-141287D01*
X1001348Y-142162D01*
X1000475Y-144204D01*
X1000038Y-145954D01*
Y-147704D01*
X1000475Y-149454D01*
X1001567Y-151204D01*
X1002877Y-152370D01*
X1004405Y-152662D01*
X1005933Y-152079D01*
X1007462Y-150329D01*
G01X1025180Y-135162D02*
Y-152662D01*
G01Y-150038D02*
X1024307Y-151496D01*
X1022996Y-152370D01*
X1021468Y-152662D01*
X1019722Y-152079D01*
X1018412Y-150621D01*
X1017538Y-148871D01*
X1017320Y-146829D01*
X1017538Y-144787D01*
X1018412Y-143037D01*
X1019722Y-141579D01*
X1021468Y-140996D01*
X1022996Y-141287D01*
X1024088Y-141871D01*
X1025180Y-143037D01*
G01X1042680Y-152662D02*
Y-140996D01*
G01Y-143037D02*
X1041807Y-141871D01*
X1040496Y-141287D01*
X1038968Y-140996D01*
X1037440Y-141579D01*
X1036130Y-142745D01*
X1035256Y-144495D01*
X1034820Y-146829D01*
X1035256Y-149162D01*
X1036130Y-150912D01*
X1037440Y-152079D01*
X1038968Y-152662D01*
X1040496Y-152370D01*
X1041807Y-151496D01*
X1042680Y-150329D01*
G01X1052538Y-152662D02*
Y-140996D01*
G01Y-143912D02*
X1053412Y-142454D01*
X1054722Y-141287D01*
X1056468Y-140996D01*
X1057996Y-141287D01*
X1059307Y-142454D01*
X1059962Y-144495D01*
Y-152662D01*
G01X1077243Y-142454D02*
X1075715Y-141287D01*
X1074405Y-140996D01*
X1072658Y-141579D01*
X1071348Y-142745D01*
X1070475Y-144787D01*
X1070256Y-146829D01*
X1070475Y-148871D01*
X1071348Y-150621D01*
X1072658Y-152079D01*
X1074405Y-152662D01*
X1075933Y-152079D01*
X1077243Y-150912D01*
G01X1087975Y-144787D02*
X1094962D01*
X1094307Y-142745D01*
X1093215Y-141579D01*
X1091687Y-140996D01*
X1090158Y-141287D01*
X1088848Y-142162D01*
X1087975Y-144204D01*
X1087538Y-145954D01*
Y-147704D01*
X1087975Y-149454D01*
X1089067Y-151204D01*
X1090377Y-152370D01*
X1091905Y-152662D01*
X1093433Y-152079D01*
X1094962Y-150329D01*
G01X1126250Y-135162D02*
Y-152662D01*
G01X1123193Y-140996D02*
X1129307D01*
G01X1140693Y-152662D02*
Y-140996D01*
G01Y-143329D02*
X1141785Y-142162D01*
X1142877Y-141287D01*
X1144405Y-140996D01*
X1145496Y-141287D01*
X1146807Y-142162D01*
G01X1165180Y-152662D02*
Y-140996D01*
G01Y-143037D02*
X1164307Y-141871D01*
X1162996Y-141287D01*
X1161468Y-140996D01*
X1159940Y-141579D01*
X1158630Y-142745D01*
X1157756Y-144495D01*
X1157320Y-146829D01*
X1157756Y-149162D01*
X1158630Y-150912D01*
X1159940Y-152079D01*
X1161468Y-152662D01*
X1162996Y-152370D01*
X1164307Y-151496D01*
X1165180Y-150329D01*
G01X1182243Y-142454D02*
X1180715Y-141287D01*
X1179405Y-140996D01*
X1177658Y-141579D01*
X1176348Y-142745D01*
X1175475Y-144787D01*
X1175256Y-146829D01*
X1175475Y-148871D01*
X1176348Y-150621D01*
X1177658Y-152079D01*
X1179405Y-152662D01*
X1180933Y-152079D01*
X1182243Y-150912D01*
G01X1192975Y-144787D02*
X1199962D01*
X1199307Y-142745D01*
X1198215Y-141579D01*
X1196687Y-140996D01*
X1195158Y-141287D01*
X1193848Y-142162D01*
X1192975Y-144204D01*
X1192538Y-145954D01*
Y-147704D01*
X1192975Y-149454D01*
X1194067Y-151204D01*
X1195377Y-152370D01*
X1196905Y-152662D01*
X1198433Y-152079D01*
X1199962Y-150329D01*
G01X1210475Y-150621D02*
X1211567Y-151787D01*
X1213095Y-152662D01*
X1214405D01*
X1215715Y-152079D01*
X1216588Y-151204D01*
X1217025Y-150038D01*
X1216807Y-148287D01*
X1215933Y-147412D01*
X1212003Y-145662D01*
X1211130Y-143620D01*
X1211567Y-142162D01*
X1212440Y-141287D01*
X1213750Y-140996D01*
X1215060Y-141287D01*
X1216370Y-142162D01*
G01X1248750Y-140996D02*
Y-152662D01*
G01Y-136329D02*
X1248313Y-136037D01*
Y-135454D01*
X1248750Y-135162D01*
X1249187Y-135454D01*
Y-136037D01*
X1248750Y-136329D01*
G01X1262538Y-152662D02*
Y-140996D01*
G01Y-143912D02*
X1263412Y-142454D01*
X1264722Y-141287D01*
X1266468Y-140996D01*
X1267996Y-141287D01*
X1269307Y-142454D01*
X1269962Y-144495D01*
Y-152662D01*
G01X1301250D02*
Y-135162D01*
G01X1322680Y-152662D02*
Y-140996D01*
G01Y-143037D02*
X1321807Y-141871D01*
X1320496Y-141287D01*
X1318968Y-140996D01*
X1317440Y-141579D01*
X1316130Y-142745D01*
X1315256Y-144495D01*
X1314820Y-146829D01*
X1315256Y-149162D01*
X1316130Y-150912D01*
X1317440Y-152079D01*
X1318968Y-152662D01*
X1320496Y-152370D01*
X1321807Y-151496D01*
X1322680Y-150329D01*
G01X1331665Y-157912D02*
X1332975Y-158495D01*
X1334722Y-157912D01*
X1335813Y-156746D01*
X1336687Y-155287D01*
X1337996Y-150621D01*
X1340835Y-140996D01*
G01X1333848D02*
X1337996Y-150621D01*
G01X1350475Y-144787D02*
X1357462D01*
X1356807Y-142745D01*
X1355715Y-141579D01*
X1354187Y-140996D01*
X1352658Y-141287D01*
X1351348Y-142162D01*
X1350475Y-144204D01*
X1350038Y-145954D01*
Y-147704D01*
X1350475Y-149454D01*
X1351567Y-151204D01*
X1352877Y-152370D01*
X1354405Y-152662D01*
X1355933Y-152079D01*
X1357462Y-150329D01*
G01X1368193Y-152662D02*
Y-140996D01*
G01Y-143329D02*
X1369285Y-142162D01*
X1370377Y-141287D01*
X1371905Y-140996D01*
X1372996Y-141287D01*
X1374307Y-142162D01*
G01X1401883Y-135162D02*
Y-152662D01*
X1410617D01*
G01X1423750D02*
X1425278Y-152370D01*
X1427025Y-151496D01*
X1428117Y-150038D01*
X1428553Y-147995D01*
X1428117Y-145954D01*
X1426807Y-144204D01*
X1424842Y-143329D01*
X1422658D01*
X1421348Y-142745D01*
X1420256Y-141287D01*
X1419820Y-139246D01*
X1420475Y-137204D01*
X1422003Y-135745D01*
X1423750Y-135162D01*
X1425496Y-135745D01*
X1427025Y-137204D01*
X1427680Y-139246D01*
X1427243Y-141287D01*
X1426152Y-142745D01*
X1424842Y-143329D01*
X1422658D01*
X1420693Y-144204D01*
X1419383Y-145954D01*
X1418947Y-147995D01*
X1419383Y-150038D01*
X1420475Y-151496D01*
X1422222Y-152370D01*
X1423750Y-152662D01*
G01X1441250Y-153245D02*
X1440813Y-152954D01*
Y-152370D01*
X1441250Y-152079D01*
X1441687Y-152370D01*
Y-152954D01*
X1441250Y-153245D01*
G01X878818Y546266D02*
Y563766D01*
X883184D01*
X884931Y562891D01*
X886241Y561724D01*
X887333Y559975D01*
X888206Y557932D01*
X888424Y555016D01*
X888206Y552099D01*
X887333Y550057D01*
X886241Y548307D01*
X884931Y547141D01*
X883184Y546266D01*
X878818D01*
G01X896754D02*
Y563766D01*
X901994D01*
X903741Y562891D01*
X905051Y560849D01*
X905488Y558516D01*
X905051Y556183D01*
X903959Y554433D01*
X901994Y553557D01*
X896754D01*
G01X933501Y563766D02*
X938741D01*
G01X936121D02*
Y546266D01*
G01X933501D02*
X938741D01*
G01X947944D02*
Y563766D01*
X953621Y549183D01*
X959298Y563766D01*
Y546266D01*
G01X966754D02*
Y563766D01*
X971994D01*
X973741Y562891D01*
X975051Y560849D01*
X975488Y558516D01*
X975051Y556183D01*
X973959Y554433D01*
X971994Y553557D01*
X966754D01*
G01X992988Y546266D02*
X984254D01*
Y563766D01*
X992988D01*
G01X989494Y555308D02*
X984254D01*
G01X1001318Y546266D02*
Y563766D01*
X1005684D01*
X1007431Y562891D01*
X1008741Y561724D01*
X1009833Y559975D01*
X1010706Y557932D01*
X1010924Y555016D01*
X1010706Y552099D01*
X1009833Y550057D01*
X1008741Y548307D01*
X1007431Y547141D01*
X1005684Y546266D01*
X1001318D01*
G01X1018162D02*
X1023621Y563766D01*
X1029080Y546266D01*
G01X1027114Y552391D02*
X1020127D01*
G01X1036099Y546266D02*
Y563766D01*
X1046143Y546266D01*
Y563766D01*
G01X1063424Y562307D02*
X1062114Y563183D01*
X1060586Y563766D01*
X1058839D01*
X1056874Y562891D01*
X1055346Y561433D01*
X1054254Y559682D01*
X1053381Y556766D01*
X1053162Y554141D01*
X1053599Y551516D01*
X1054254Y549766D01*
X1055564Y548016D01*
X1057093Y546849D01*
X1058621Y546266D01*
X1060149D01*
X1061678Y546849D01*
X1062988Y547724D01*
X1064080Y548890D01*
G01X1080488Y546266D02*
X1071754D01*
Y563766D01*
X1080488D01*
G01X1076994Y555308D02*
X1071754D01*
G01X1111121Y563766D02*
Y546266D01*
G01X1106099Y563766D02*
X1116143D01*
G01X1123162Y546266D02*
X1128621Y563766D01*
X1134080Y546266D01*
G01X1132114Y552391D02*
X1125127D01*
G01X1147867Y555599D02*
X1148741Y556474D01*
X1149396Y557932D01*
X1149833Y559975D01*
X1149396Y561724D01*
X1148523Y562891D01*
X1146994Y563766D01*
X1141099D01*
Y546266D01*
X1148304D01*
X1149833Y547432D01*
X1150706Y549183D01*
X1151143Y551224D01*
X1150706Y553266D01*
X1149396Y555016D01*
X1147867Y555599D01*
X1141099D01*
G01X1159254Y563766D02*
Y546266D01*
X1167988D01*
G01X1185488D02*
X1176754D01*
Y563766D01*
X1185488D01*
G01X1181994Y555308D02*
X1176754D01*
G01X1198621Y545683D02*
X1198184Y545974D01*
Y546558D01*
X1198621Y546849D01*
X1199058Y546558D01*
Y545974D01*
X1198621Y545683D01*
G01Y553557D02*
X1198184Y553849D01*
Y554433D01*
X1198621Y554724D01*
X1199058Y554433D01*
Y553849D01*
X1198621Y553557D01*
G01X1229254Y563766D02*
Y546266D01*
X1237988D01*
G01X1251121D02*
X1252649Y546558D01*
X1254396Y547432D01*
X1255488Y548890D01*
X1255924Y550933D01*
X1255488Y552974D01*
X1254178Y554724D01*
X1252213Y555599D01*
X1250029D01*
X1248719Y556183D01*
X1247627Y557641D01*
X1247191Y559682D01*
X1247846Y561724D01*
X1249374Y563183D01*
X1251121Y563766D01*
X1252867Y563183D01*
X1254396Y561724D01*
X1255051Y559682D01*
X1254614Y557641D01*
X1253523Y556183D01*
X1252213Y555599D01*
X1250029D01*
X1248064Y554724D01*
X1246754Y552974D01*
X1246318Y550933D01*
X1246754Y548890D01*
X1247846Y547432D01*
X1249593Y546558D01*
X1251121Y546266D01*
G01X924768Y407083D02*
X934374Y419916D01*
G01X929571Y422249D02*
Y404749D01*
G01X934374Y407083D02*
X924768Y419916D01*
G01X923021Y413499D02*
X936121D01*
G01X943359Y409707D02*
X944888Y408249D01*
X946634Y407666D01*
X948381Y408249D01*
X949909Y409999D01*
X951001Y412624D01*
X951438Y415249D01*
Y418457D01*
X951001Y421082D01*
X949909Y423416D01*
X948599Y424583D01*
X947071Y425166D01*
X945324Y424583D01*
X944014Y423416D01*
X943141Y421666D01*
X942704Y419332D01*
X943141Y417291D01*
X944233Y415249D01*
X945543Y414082D01*
X947071Y413791D01*
X948817Y414374D01*
X950128Y415833D01*
X951438Y418457D01*
G01X964134Y407666D02*
X964571Y411457D01*
X965226Y414666D01*
X966099Y417583D01*
X967191Y420791D01*
X968938Y425166D01*
X960204D01*
G01X982071Y407083D02*
X981634Y407374D01*
Y407958D01*
X982071Y408249D01*
X982508Y407958D01*
Y407374D01*
X982071Y407083D01*
G01X999571Y425166D02*
X997824Y424583D01*
X996514Y423124D01*
X995641Y421375D01*
X994986Y419041D01*
X994768Y416416D01*
X994986Y413791D01*
X995641Y411457D01*
X996514Y409707D01*
X997824Y408249D01*
X999571Y407666D01*
X1001317Y408249D01*
X1002628Y409707D01*
X1003501Y411457D01*
X1004156Y413791D01*
X1004374Y416416D01*
X1004156Y419041D01*
X1003501Y421375D01*
X1002628Y423124D01*
X1001317Y424583D01*
X999571Y425166D01*
G01X929571Y373016D02*
Y390516D01*
X926951Y387016D01*
G01Y373016D02*
X932191D01*
G01X947071Y390516D02*
X945324Y389933D01*
X944014Y388474D01*
X943141Y386725D01*
X942486Y384391D01*
X942268Y381766D01*
X942486Y379141D01*
X943141Y376807D01*
X944014Y375057D01*
X945324Y373599D01*
X947071Y373016D01*
X948817Y373599D01*
X950128Y375057D01*
X951001Y376807D01*
X951656Y379141D01*
X951874Y381766D01*
X951656Y384391D01*
X951001Y386725D01*
X950128Y388474D01*
X948817Y389933D01*
X947071Y390516D01*
G01X964571D02*
X962824Y389933D01*
X961514Y388474D01*
X960641Y386725D01*
X959986Y384391D01*
X959768Y381766D01*
X959986Y379141D01*
X960641Y376807D01*
X961514Y375057D01*
X962824Y373599D01*
X964571Y373016D01*
X966317Y373599D01*
X967628Y375057D01*
X968501Y376807D01*
X969156Y379141D01*
X969374Y381766D01*
X969156Y384391D01*
X968501Y386725D01*
X967628Y388474D01*
X966317Y389933D01*
X964571Y390516D01*
G01X982071Y372433D02*
X981634Y372724D01*
Y373308D01*
X982071Y373599D01*
X982508Y373308D01*
Y372724D01*
X982071Y372433D01*
G01X999571Y390516D02*
X997824Y389933D01*
X996514Y388474D01*
X995641Y386725D01*
X994986Y384391D01*
X994768Y381766D01*
X994986Y379141D01*
X995641Y376807D01*
X996514Y375057D01*
X997824Y373599D01*
X999571Y373016D01*
X1001317Y373599D01*
X1002628Y375057D01*
X1003501Y376807D01*
X1004156Y379141D01*
X1004374Y381766D01*
X1004156Y384391D01*
X1003501Y386725D01*
X1002628Y388474D01*
X1001317Y389933D01*
X999571Y390516D01*
G01X938321Y476966D02*
X939849Y477258D01*
X941596Y478132D01*
X942688Y479590D01*
X943124Y481633D01*
X942688Y483674D01*
X941378Y485424D01*
X939413Y486299D01*
X937229D01*
X935919Y486883D01*
X934827Y488341D01*
X934391Y490382D01*
X935046Y492424D01*
X936574Y493883D01*
X938321Y494466D01*
X940067Y493883D01*
X941596Y492424D01*
X942251Y490382D01*
X941814Y488341D01*
X940723Y486883D01*
X939413Y486299D01*
X937229D01*
X935264Y485424D01*
X933954Y483674D01*
X933518Y481633D01*
X933954Y479590D01*
X935046Y478132D01*
X936793Y477258D01*
X938321Y476966D01*
G01X951018Y479590D02*
X952327Y478132D01*
X953856Y477258D01*
X955821Y476966D01*
X957786Y477549D01*
X959314Y478716D01*
X960406Y480757D01*
X960624Y483091D01*
X960188Y485424D01*
X959096Y486883D01*
X957567Y488049D01*
X956039Y488341D01*
X954511Y488049D01*
X952546Y486883D01*
X953201Y494466D01*
X959096D01*
G01X973321Y476383D02*
X972884Y476674D01*
Y477258D01*
X973321Y477549D01*
X973758Y477258D01*
Y476674D01*
X973321Y476383D01*
G01X990821Y494466D02*
X989074Y493883D01*
X987764Y492424D01*
X986891Y490675D01*
X986236Y488341D01*
X986018Y485716D01*
X986236Y483091D01*
X986891Y480757D01*
X987764Y479007D01*
X989074Y477549D01*
X990821Y476966D01*
X992567Y477549D01*
X993878Y479007D01*
X994751Y480757D01*
X995406Y483091D01*
X995624Y485716D01*
X995406Y488341D01*
X994751Y490675D01*
X993878Y492424D01*
X992567Y493883D01*
X990821Y494466D01*
G01X924768Y441733D02*
X934374Y454566D01*
G01X929571Y456899D02*
Y439399D01*
G01X934374Y441733D02*
X924768Y454566D01*
G01X923021Y448149D02*
X936121D01*
G01X943359Y444357D02*
X944888Y442899D01*
X946634Y442316D01*
X948381Y442899D01*
X949909Y444649D01*
X951001Y447274D01*
X951438Y449899D01*
Y453107D01*
X951001Y455732D01*
X949909Y458066D01*
X948599Y459233D01*
X947071Y459816D01*
X945324Y459233D01*
X944014Y458066D01*
X943141Y456316D01*
X942704Y453982D01*
X943141Y451941D01*
X944233Y449899D01*
X945543Y448732D01*
X947071Y448441D01*
X948817Y449024D01*
X950128Y450483D01*
X951438Y453107D01*
G01X960423Y456899D02*
X961733Y458649D01*
X963261Y459524D01*
X965008Y459816D01*
X967191Y459233D01*
X968719Y457774D01*
X969156Y456025D01*
X968938Y454274D01*
X968064Y452816D01*
X963698Y449899D01*
X961733Y447858D01*
X960423Y444940D01*
X959986Y442316D01*
X969156D01*
G01X982071Y441733D02*
X981634Y442024D01*
Y442608D01*
X982071Y442899D01*
X982508Y442608D01*
Y442024D01*
X982071Y441733D01*
G01X999571Y459816D02*
X997824Y459233D01*
X996514Y457774D01*
X995641Y456025D01*
X994986Y453691D01*
X994768Y451066D01*
X994986Y448441D01*
X995641Y446107D01*
X996514Y444357D01*
X997824Y442899D01*
X999571Y442316D01*
X1001317Y442899D01*
X1002628Y444357D01*
X1003501Y446107D01*
X1004156Y448441D01*
X1004374Y451066D01*
X1004156Y453691D01*
X1003501Y456025D01*
X1002628Y457774D01*
X1001317Y459233D01*
X999571Y459816D01*
G01X900701Y529116D02*
X905941D01*
G01X903321D02*
Y511616D01*
G01X900701D02*
X905941D01*
G01X915144D02*
Y529116D01*
X920821Y514533D01*
X926498Y529116D01*
Y511616D01*
G01X933954D02*
Y529116D01*
X939194D01*
X940941Y528241D01*
X942251Y526199D01*
X942688Y523866D01*
X942251Y521533D01*
X941159Y519783D01*
X939194Y518907D01*
X933954D01*
G01X954729Y505783D02*
X952546Y508699D01*
X951454Y511616D01*
Y523282D01*
X952546Y526199D01*
X954729Y529116D01*
G01X973321Y511616D02*
X971574Y511908D01*
X970046Y513074D01*
X968736Y514824D01*
X967862Y516866D01*
X967426Y519199D01*
Y521533D01*
X967862Y523866D01*
X968736Y525908D01*
X970046Y527657D01*
X971574Y528824D01*
X973321Y529116D01*
X975067Y528824D01*
X976596Y527657D01*
X977906Y525908D01*
X978780Y523866D01*
X979216Y521533D01*
Y519199D01*
X978780Y516866D01*
X977906Y514824D01*
X976596Y513074D01*
X975067Y511908D01*
X973321Y511616D01*
G01X987109D02*
Y529116D01*
G01Y520658D02*
X988201Y522116D01*
X989293Y522991D01*
X991039Y523282D01*
X992349Y522991D01*
X993878Y521824D01*
X994533Y520074D01*
Y511616D01*
G01X1001771D02*
Y523282D01*
G01Y520074D02*
X1002426Y521533D01*
X1003518Y522699D01*
X1005046Y523282D01*
X1006574Y522699D01*
X1007666Y521533D01*
X1008321Y520074D01*
Y511616D01*
G01Y520074D02*
X1008976Y521533D01*
X1010067Y522699D01*
X1011596Y523282D01*
X1013124Y522699D01*
X1014216Y521533D01*
X1014871Y519783D01*
Y511616D01*
G01X1026913Y505783D02*
X1029096Y508699D01*
X1030188Y511616D01*
Y523282D01*
X1029096Y526199D01*
X1026913Y529116D01*
G01X1126018Y411166D02*
X1127327Y409124D01*
X1129074Y407958D01*
X1131039Y407666D01*
X1132786Y407958D01*
X1134533Y409416D01*
X1135624Y411166D01*
X1135843Y412916D01*
X1135406Y414957D01*
X1133878Y416416D01*
X1132349Y416999D01*
X1130384D01*
G01X1132349D02*
X1133659Y417874D01*
X1134751Y419332D01*
X1135188Y421082D01*
X1134751Y422833D01*
X1133659Y424291D01*
X1131694Y425166D01*
X1129729Y424874D01*
X1127764Y423707D01*
G01X1148321Y407083D02*
X1147884Y407374D01*
Y407958D01*
X1148321Y408249D01*
X1148758Y407958D01*
Y407374D01*
X1148321Y407083D01*
G01X1161018Y410290D02*
X1162327Y408832D01*
X1163856Y407958D01*
X1165821Y407666D01*
X1167786Y408249D01*
X1169314Y409416D01*
X1170406Y411457D01*
X1170624Y413791D01*
X1170188Y416124D01*
X1169096Y417583D01*
X1167567Y418749D01*
X1166039Y419041D01*
X1164511Y418749D01*
X1162546Y417583D01*
X1163201Y425166D01*
X1169096D01*
G01X1179391Y407083D02*
X1187251Y425166D01*
G01X1203441Y407666D02*
Y425166D01*
X1195362Y412624D01*
X1206280D01*
G01X1218321Y407083D02*
X1217884Y407374D01*
Y407958D01*
X1218321Y408249D01*
X1218758Y407958D01*
Y407374D01*
X1218321Y407083D01*
G01X1235821Y425166D02*
X1234074Y424583D01*
X1232764Y423124D01*
X1231891Y421375D01*
X1231236Y419041D01*
X1231018Y416416D01*
X1231236Y413791D01*
X1231891Y411457D01*
X1232764Y409707D01*
X1234074Y408249D01*
X1235821Y407666D01*
X1237567Y408249D01*
X1238878Y409707D01*
X1239751Y411457D01*
X1240406Y413791D01*
X1240624Y416416D01*
X1240406Y419041D01*
X1239751Y421375D01*
X1238878Y423124D01*
X1237567Y424583D01*
X1235821Y425166D01*
G01X1124691Y373016D02*
Y390516D01*
X1116612Y377974D01*
X1127530D01*
G01X1139571Y372433D02*
X1139134Y372724D01*
Y373308D01*
X1139571Y373599D01*
X1140008Y373308D01*
Y372724D01*
X1139571Y372433D01*
G01X1153359Y375057D02*
X1154888Y373599D01*
X1156634Y373016D01*
X1158381Y373599D01*
X1159909Y375349D01*
X1161001Y377974D01*
X1161438Y380599D01*
Y383807D01*
X1161001Y386432D01*
X1159909Y388766D01*
X1158599Y389933D01*
X1157071Y390516D01*
X1155324Y389933D01*
X1154014Y388766D01*
X1153141Y387016D01*
X1152704Y384682D01*
X1153141Y382641D01*
X1154233Y380599D01*
X1155543Y379432D01*
X1157071Y379141D01*
X1158817Y379724D01*
X1160128Y381183D01*
X1161438Y383807D01*
G01X1170641Y372433D02*
X1178501Y390516D01*
G01X1192071Y373016D02*
Y390516D01*
X1189451Y387016D01*
G01Y373016D02*
X1194691D01*
G01X1209571D02*
Y390516D01*
X1206951Y387016D01*
G01Y373016D02*
X1212191D01*
G01X1227071Y372433D02*
X1226634Y372724D01*
Y373308D01*
X1227071Y373599D01*
X1227508Y373308D01*
Y372724D01*
X1227071Y372433D01*
G01X1244571Y373016D02*
Y390516D01*
X1241951Y387016D01*
G01Y373016D02*
X1247191D01*
G01X1117268Y479590D02*
X1118577Y478132D01*
X1120106Y477258D01*
X1122071Y476966D01*
X1124036Y477549D01*
X1125564Y478716D01*
X1126656Y480757D01*
X1126874Y483091D01*
X1126438Y485424D01*
X1125346Y486883D01*
X1123817Y488049D01*
X1122289Y488341D01*
X1120761Y488049D01*
X1118796Y486883D01*
X1119451Y494466D01*
X1125346D01*
G01X1139571Y476383D02*
X1139134Y476674D01*
Y477258D01*
X1139571Y477549D01*
X1140008Y477258D01*
Y476674D01*
X1139571Y476383D01*
G01X1156634Y476966D02*
X1157071Y480757D01*
X1157726Y483966D01*
X1158599Y486883D01*
X1159691Y490091D01*
X1161438Y494466D01*
X1152704D01*
G01X1169768Y479590D02*
X1171077Y478132D01*
X1172606Y477258D01*
X1174571Y476966D01*
X1176536Y477549D01*
X1178064Y478716D01*
X1179156Y480757D01*
X1179374Y483091D01*
X1178938Y485424D01*
X1177846Y486883D01*
X1176317Y488049D01*
X1174789Y488341D01*
X1173261Y488049D01*
X1171296Y486883D01*
X1171951Y494466D01*
X1177846D01*
G01X1188141Y476383D02*
X1196001Y494466D01*
G01X1205423Y484257D02*
X1206951Y486299D01*
X1208261Y487466D01*
X1210008Y488049D01*
X1211536Y487466D01*
X1212628Y486299D01*
X1213501Y484549D01*
X1213719Y482508D01*
X1213501Y480757D01*
X1212628Y479007D01*
X1211317Y477549D01*
X1209789Y476966D01*
X1208043Y477549D01*
X1206514Y479299D01*
X1205641Y481924D01*
X1205423Y484841D01*
X1205859Y488632D01*
X1206514Y490675D01*
X1207606Y492716D01*
X1209134Y494174D01*
X1210663Y494466D01*
X1212191Y493883D01*
X1213283Y492424D01*
G01X1227071Y476383D02*
X1226634Y476674D01*
Y477258D01*
X1227071Y477549D01*
X1227508Y477258D01*
Y476674D01*
X1227071Y476383D01*
G01X1239768Y479590D02*
X1241077Y478132D01*
X1242606Y477258D01*
X1244571Y476966D01*
X1246536Y477549D01*
X1248064Y478716D01*
X1249156Y480757D01*
X1249374Y483091D01*
X1248938Y485424D01*
X1247846Y486883D01*
X1246317Y488049D01*
X1244789Y488341D01*
X1243261Y488049D01*
X1241296Y486883D01*
X1241951Y494466D01*
X1247846D01*
G01X1117268Y445816D02*
X1118577Y443774D01*
X1120324Y442608D01*
X1122289Y442316D01*
X1124036Y442608D01*
X1125783Y444066D01*
X1126874Y445816D01*
X1127093Y447566D01*
X1126656Y449607D01*
X1125128Y451066D01*
X1123599Y451649D01*
X1121634D01*
G01X1123599D02*
X1124909Y452524D01*
X1126001Y453982D01*
X1126438Y455732D01*
X1126001Y457483D01*
X1124909Y458941D01*
X1122944Y459816D01*
X1120979Y459524D01*
X1119014Y458357D01*
G01X1139571Y441733D02*
X1139134Y442024D01*
Y442608D01*
X1139571Y442899D01*
X1140008Y442608D01*
Y442024D01*
X1139571Y441733D01*
G01X1156634Y442316D02*
X1157071Y446107D01*
X1157726Y449316D01*
X1158599Y452233D01*
X1159691Y455441D01*
X1161438Y459816D01*
X1152704D01*
G01X1169768Y444940D02*
X1171077Y443482D01*
X1172606Y442608D01*
X1174571Y442316D01*
X1176536Y442899D01*
X1178064Y444066D01*
X1179156Y446107D01*
X1179374Y448441D01*
X1178938Y450774D01*
X1177846Y452233D01*
X1176317Y453399D01*
X1174789Y453691D01*
X1173261Y453399D01*
X1171296Y452233D01*
X1171951Y459816D01*
X1177846D01*
G01X1188141Y441733D02*
X1196001Y459816D01*
G01X1204768Y445816D02*
X1206077Y443774D01*
X1207824Y442608D01*
X1209789Y442316D01*
X1211536Y442608D01*
X1213283Y444066D01*
X1214374Y445816D01*
X1214593Y447566D01*
X1214156Y449607D01*
X1212628Y451066D01*
X1211099Y451649D01*
X1209134D01*
G01X1211099D02*
X1212409Y452524D01*
X1213501Y453982D01*
X1213938Y455732D01*
X1213501Y457483D01*
X1212409Y458941D01*
X1210444Y459816D01*
X1208479Y459524D01*
X1206514Y458357D01*
G01X1227071Y441733D02*
X1226634Y442024D01*
Y442608D01*
X1227071Y442899D01*
X1227508Y442608D01*
Y442024D01*
X1227071Y441733D01*
G01X1239768Y444940D02*
X1241077Y443482D01*
X1242606Y442608D01*
X1244571Y442316D01*
X1246536Y442899D01*
X1248064Y444066D01*
X1249156Y446107D01*
X1249374Y448441D01*
X1248938Y450774D01*
X1247846Y452233D01*
X1246317Y453399D01*
X1244789Y453691D01*
X1243261Y453399D01*
X1241296Y452233D01*
X1241951Y459816D01*
X1247846D01*
G01X1089271Y529116D02*
X1092327Y511616D01*
X1095821Y529116D01*
X1099314Y511616D01*
X1102371Y529116D01*
G01X1110701D02*
X1115941D01*
G01X1113321D02*
Y511616D01*
G01X1110701D02*
X1115941D01*
G01X1126018D02*
Y529116D01*
X1130384D01*
X1132131Y528241D01*
X1133441Y527074D01*
X1134533Y525325D01*
X1135406Y523282D01*
X1135624Y520366D01*
X1135406Y517449D01*
X1134533Y515407D01*
X1133441Y513657D01*
X1132131Y512491D01*
X1130384Y511616D01*
X1126018D01*
G01X1148321Y529116D02*
Y511616D01*
G01X1143299Y529116D02*
X1153343D01*
G01X1161236Y511616D02*
Y529116D01*
G01X1170406D02*
Y511616D01*
G01Y520366D02*
X1161236D01*
G01X1182229Y505783D02*
X1180046Y508699D01*
X1178954Y511616D01*
Y523282D01*
X1180046Y526199D01*
X1182229Y529116D01*
G01X1194271Y511616D02*
Y523282D01*
G01Y520074D02*
X1194926Y521533D01*
X1196018Y522699D01*
X1197546Y523282D01*
X1199074Y522699D01*
X1200166Y521533D01*
X1200821Y520074D01*
Y511616D01*
G01Y520074D02*
X1201476Y521533D01*
X1202567Y522699D01*
X1204096Y523282D01*
X1205624Y522699D01*
X1206716Y521533D01*
X1207371Y519783D01*
Y511616D01*
G01X1218321Y523282D02*
Y511616D01*
G01Y527949D02*
X1217884Y528241D01*
Y528824D01*
X1218321Y529116D01*
X1218758Y528824D01*
Y528241D01*
X1218321Y527949D01*
G01X1235821Y511616D02*
Y529116D01*
G01X1250046Y513657D02*
X1251138Y512491D01*
X1252666Y511616D01*
X1253976D01*
X1255286Y512199D01*
X1256159Y513074D01*
X1256596Y514240D01*
X1256378Y515991D01*
X1255504Y516866D01*
X1251574Y518616D01*
X1250701Y520658D01*
X1251138Y522116D01*
X1252011Y522991D01*
X1253321Y523282D01*
X1254631Y522991D01*
X1255941Y522116D01*
G01X1271913Y505783D02*
X1274096Y508699D01*
X1275188Y511616D01*
Y523282D01*
X1274096Y526199D01*
X1271913Y529116D01*
G01X1353518Y407666D02*
Y425166D01*
X1357884D01*
X1359631Y424291D01*
X1360941Y423124D01*
X1362033Y421375D01*
X1362906Y419332D01*
X1363124Y416416D01*
X1362906Y413499D01*
X1362033Y411457D01*
X1360941Y409707D01*
X1359631Y408541D01*
X1357884Y407666D01*
X1353518D01*
G01X1371454D02*
Y425166D01*
X1376694D01*
X1378441Y424291D01*
X1379751Y422249D01*
X1380188Y419916D01*
X1379751Y417583D01*
X1378659Y415833D01*
X1376694Y414957D01*
X1371454D01*
G01X1353518Y373016D02*
Y390516D01*
X1357884D01*
X1359631Y389641D01*
X1360941Y388474D01*
X1362033Y386725D01*
X1362906Y384682D01*
X1363124Y381766D01*
X1362906Y378849D01*
X1362033Y376807D01*
X1360941Y375057D01*
X1359631Y373891D01*
X1357884Y373016D01*
X1353518D01*
G01X1371454D02*
Y390516D01*
X1376694D01*
X1378441Y389641D01*
X1379751Y387599D01*
X1380188Y385266D01*
X1379751Y382933D01*
X1378659Y381183D01*
X1376694Y380307D01*
X1371454D01*
G01X1353518Y476966D02*
Y494466D01*
X1357884D01*
X1359631Y493591D01*
X1360941Y492424D01*
X1362033Y490675D01*
X1362906Y488632D01*
X1363124Y485716D01*
X1362906Y482799D01*
X1362033Y480757D01*
X1360941Y479007D01*
X1359631Y477841D01*
X1357884Y476966D01*
X1353518D01*
G01X1371454D02*
Y494466D01*
X1376694D01*
X1378441Y493591D01*
X1379751Y491549D01*
X1380188Y489216D01*
X1379751Y486883D01*
X1378659Y485133D01*
X1376694Y484257D01*
X1371454D01*
G01X1353518Y442316D02*
Y459816D01*
X1357884D01*
X1359631Y458941D01*
X1360941Y457774D01*
X1362033Y456025D01*
X1362906Y453982D01*
X1363124Y451066D01*
X1362906Y448149D01*
X1362033Y446107D01*
X1360941Y444357D01*
X1359631Y443191D01*
X1357884Y442316D01*
X1353518D01*
G01X1371454D02*
Y459816D01*
X1376694D01*
X1378441Y458941D01*
X1379751Y456899D01*
X1380188Y454566D01*
X1379751Y452233D01*
X1378659Y450483D01*
X1376694Y449607D01*
X1371454D01*
G01X1340821Y529116D02*
Y511616D01*
G01X1335799Y529116D02*
X1345843D01*
G01X1358321Y511616D02*
Y519491D01*
X1353954Y529116D01*
G01X1362688D02*
X1358321Y519491D01*
G01X1371454Y511616D02*
Y529116D01*
X1376694D01*
X1378441Y528241D01*
X1379751Y526199D01*
X1380188Y523866D01*
X1379751Y521533D01*
X1378659Y519783D01*
X1376694Y518907D01*
X1371454D01*
G01X1397688Y511616D02*
X1388954D01*
Y529116D01*
X1397688D01*
G01X1394194Y520658D02*
X1388954D01*
G01X1441454Y511616D02*
Y529116D01*
X1446913D01*
X1448659Y528241D01*
X1449751Y527074D01*
X1450188Y524741D01*
X1449751Y522407D01*
X1448441Y520949D01*
X1446913Y520074D01*
X1441454D01*
G01X1446913D02*
X1450188Y511616D01*
G01X1460046Y519491D02*
X1467033D01*
X1466378Y521533D01*
X1465286Y522699D01*
X1463758Y523282D01*
X1462229Y522991D01*
X1460919Y522116D01*
X1460046Y520074D01*
X1459609Y518324D01*
Y516574D01*
X1460046Y514824D01*
X1461138Y513074D01*
X1462448Y511908D01*
X1463976Y511616D01*
X1465504Y512199D01*
X1467033Y513949D01*
G01X1479511Y511616D02*
Y526491D01*
X1479948Y527949D01*
X1480821Y528824D01*
X1482131Y529116D01*
X1483441Y528533D01*
X1484096Y527074D01*
G01X1481476Y522116D02*
X1477109D01*
G01X1498321Y511033D02*
X1497884Y511324D01*
Y511908D01*
X1498321Y512199D01*
X1498758Y511908D01*
Y511324D01*
X1498321Y511033D01*
G01X1528954Y511616D02*
Y529116D01*
X1534194D01*
X1535941Y528241D01*
X1537251Y526199D01*
X1537688Y523866D01*
X1537251Y521533D01*
X1536159Y519783D01*
X1534194Y518907D01*
X1528954D01*
G01X1550821Y511616D02*
Y529116D01*
G01X1572251Y511616D02*
Y523282D01*
G01Y521241D02*
X1571378Y522407D01*
X1570067Y522991D01*
X1568539Y523282D01*
X1567011Y522699D01*
X1565701Y521533D01*
X1564827Y519783D01*
X1564391Y517449D01*
X1564827Y515116D01*
X1565701Y513366D01*
X1567011Y512199D01*
X1568539Y511616D01*
X1570067Y511908D01*
X1571378Y512782D01*
X1572251Y513949D01*
G01X1582109Y511616D02*
Y523282D01*
G01Y520366D02*
X1582983Y521824D01*
X1584293Y522991D01*
X1586039Y523282D01*
X1587567Y522991D01*
X1588878Y521824D01*
X1589533Y519783D01*
Y511616D01*
G01X1600046Y519491D02*
X1607033D01*
X1606378Y521533D01*
X1605286Y522699D01*
X1603758Y523282D01*
X1602229Y522991D01*
X1600919Y522116D01*
X1600046Y520074D01*
X1599609Y518324D01*
Y516574D01*
X1600046Y514824D01*
X1601138Y513074D01*
X1602448Y511908D01*
X1603976Y511616D01*
X1605504Y512199D01*
X1607033Y513949D01*
G01X1511454Y425166D02*
Y407666D01*
X1520188D01*
G01X1532884D02*
X1533321Y411457D01*
X1533976Y414666D01*
X1534849Y417583D01*
X1535941Y420791D01*
X1537688Y425166D01*
X1528954D01*
G01X1511454Y390516D02*
Y373016D01*
X1520188D01*
G01X1532884D02*
X1533321Y376807D01*
X1533976Y380016D01*
X1534849Y382933D01*
X1535941Y386141D01*
X1537688Y390516D01*
X1528954D01*
G01X1511454Y494466D02*
Y476966D01*
X1520188D01*
G01X1532884D02*
X1533321Y480757D01*
X1533976Y483966D01*
X1534849Y486883D01*
X1535941Y490091D01*
X1537688Y494466D01*
X1528954D01*
G01X1511454Y459816D02*
Y442316D01*
X1520188D01*
G01X1532884D02*
X1533321Y446107D01*
X1533976Y449316D01*
X1534849Y452233D01*
X1535941Y455441D01*
X1537688Y459816D01*
X1528954D01*
G01X1721121Y488632D02*
Y476966D01*
G01Y493299D02*
X1720684Y493591D01*
Y494174D01*
X1721121Y494466D01*
X1721558Y494174D01*
Y493591D01*
X1721121Y493299D01*
G01X1735346Y479007D02*
X1736438Y477841D01*
X1737966Y476966D01*
X1739276D01*
X1740586Y477549D01*
X1741459Y478424D01*
X1741896Y479590D01*
X1741678Y481341D01*
X1740804Y482216D01*
X1736874Y483966D01*
X1736001Y486008D01*
X1736438Y487466D01*
X1737311Y488341D01*
X1738621Y488632D01*
X1739931Y488341D01*
X1741241Y487466D01*
G01X1768599Y476966D02*
Y494466D01*
X1778643Y476966D01*
Y494466D01*
G01X1791121Y476966D02*
X1789374Y477258D01*
X1787846Y478424D01*
X1786536Y480174D01*
X1785662Y482216D01*
X1785226Y484549D01*
Y486883D01*
X1785662Y489216D01*
X1786536Y491258D01*
X1787846Y493007D01*
X1789374Y494174D01*
X1791121Y494466D01*
X1792867Y494174D01*
X1794396Y493007D01*
X1795706Y491258D01*
X1796580Y489216D01*
X1797016Y486883D01*
Y484549D01*
X1796580Y482216D01*
X1795706Y480174D01*
X1794396Y478424D01*
X1792867Y477258D01*
X1791121Y476966D01*
G01X1808621Y494466D02*
Y476966D01*
G01X1803599Y494466D02*
X1813643D01*
G01X1839909Y488632D02*
Y480466D01*
X1840783Y478424D01*
X1842093Y477258D01*
X1843621Y476966D01*
X1845149Y477258D01*
X1846459Y478424D01*
X1847333Y480466D01*
G01Y476966D02*
Y488632D01*
G01X1857846Y479007D02*
X1858938Y477841D01*
X1860466Y476966D01*
X1861776D01*
X1863086Y477549D01*
X1863959Y478424D01*
X1864396Y479590D01*
X1864178Y481341D01*
X1863304Y482216D01*
X1859374Y483966D01*
X1858501Y486008D01*
X1858938Y487466D01*
X1859811Y488341D01*
X1861121Y488632D01*
X1862431Y488341D01*
X1863741Y487466D01*
G01X1875346Y484841D02*
X1882333D01*
X1881678Y486883D01*
X1880586Y488049D01*
X1879058Y488632D01*
X1877529Y488341D01*
X1876219Y487466D01*
X1875346Y485424D01*
X1874909Y483674D01*
Y481924D01*
X1875346Y480174D01*
X1876438Y478424D01*
X1877748Y477258D01*
X1879276Y476966D01*
X1880804Y477549D01*
X1882333Y479299D01*
G01X1900051Y494466D02*
Y476966D01*
G01Y479590D02*
X1899178Y478132D01*
X1897867Y477258D01*
X1896339Y476966D01*
X1894593Y477549D01*
X1893283Y479007D01*
X1892409Y480757D01*
X1892191Y482799D01*
X1892409Y484841D01*
X1893283Y486591D01*
X1894593Y488049D01*
X1896339Y488632D01*
X1897867Y488341D01*
X1898959Y487757D01*
X1900051Y486591D01*
G01X1646318Y511033D02*
X1655924Y523866D01*
G01X1651121Y526199D02*
Y508699D01*
G01X1655924Y511033D02*
X1646318Y523866D01*
G01X1644571Y517449D02*
X1657671D01*
G01X1683283D02*
X1688959D01*
G01X1716318Y511616D02*
Y529116D01*
X1720684D01*
X1722431Y528241D01*
X1723741Y527074D01*
X1724833Y525325D01*
X1725706Y523282D01*
X1725924Y520366D01*
X1725706Y517449D01*
X1724833Y515407D01*
X1723741Y513657D01*
X1722431Y512491D01*
X1720684Y511616D01*
X1716318D01*
G01X1735346Y519491D02*
X1742333D01*
X1741678Y521533D01*
X1740586Y522699D01*
X1739058Y523282D01*
X1737529Y522991D01*
X1736219Y522116D01*
X1735346Y520074D01*
X1734909Y518324D01*
Y516574D01*
X1735346Y514824D01*
X1736438Y513074D01*
X1737748Y511908D01*
X1739276Y511616D01*
X1740804Y512199D01*
X1742333Y513949D01*
G01X1752409Y511616D02*
Y523282D01*
G01Y520366D02*
X1753283Y521824D01*
X1754593Y522991D01*
X1756339Y523282D01*
X1757867Y522991D01*
X1759178Y521824D01*
X1759833Y519783D01*
Y511616D01*
G01X1773621D02*
X1772311Y511908D01*
X1771001Y513074D01*
X1770127Y515116D01*
X1769691Y517449D01*
X1770127Y519783D01*
X1771001Y521824D01*
X1772311Y522991D01*
X1773621Y523282D01*
X1774931Y522991D01*
X1776241Y521824D01*
X1777114Y519783D01*
X1777333Y517449D01*
X1777114Y515116D01*
X1776241Y513074D01*
X1774931Y511908D01*
X1773621Y511616D01*
G01X1791121Y529116D02*
Y511616D01*
G01X1788064Y523282D02*
X1794178D01*
G01X1805346Y519491D02*
X1812333D01*
X1811678Y521533D01*
X1810586Y522699D01*
X1809058Y523282D01*
X1807529Y522991D01*
X1806219Y522116D01*
X1805346Y520074D01*
X1804909Y518324D01*
Y516574D01*
X1805346Y514824D01*
X1806438Y513074D01*
X1807748Y511908D01*
X1809276Y511616D01*
X1810804Y512199D01*
X1812333Y513949D01*
G01X1822846Y513657D02*
X1823938Y512491D01*
X1825466Y511616D01*
X1826776D01*
X1828086Y512199D01*
X1828959Y513074D01*
X1829396Y514240D01*
X1829178Y515991D01*
X1828304Y516866D01*
X1824374Y518616D01*
X1823501Y520658D01*
X1823938Y522116D01*
X1824811Y522991D01*
X1826121Y523282D01*
X1827431Y522991D01*
X1828741Y522116D01*
G01X1861121Y529116D02*
Y511616D01*
G01X1858064Y523282D02*
X1864178D01*
G01X1874909Y511616D02*
Y529116D01*
G01Y520658D02*
X1876001Y522116D01*
X1877093Y522991D01*
X1878839Y523282D01*
X1880149Y522991D01*
X1881678Y521824D01*
X1882333Y520074D01*
Y511616D01*
G01X1900051D02*
Y523282D01*
G01Y521241D02*
X1899178Y522407D01*
X1897867Y522991D01*
X1896339Y523282D01*
X1894811Y522699D01*
X1893501Y521533D01*
X1892627Y519783D01*
X1892191Y517449D01*
X1892627Y515116D01*
X1893501Y513366D01*
X1894811Y512199D01*
X1896339Y511616D01*
X1897867Y511908D01*
X1899178Y512782D01*
X1900051Y513949D01*
G01X1913621Y529116D02*
Y511616D01*
G01X1910564Y523282D02*
X1916678D01*
G01X1948621Y529116D02*
Y511616D01*
G01X1945564Y523282D02*
X1951678D01*
G01X1962409Y511616D02*
Y529116D01*
G01Y520658D02*
X1963501Y522116D01*
X1964593Y522991D01*
X1966339Y523282D01*
X1967649Y522991D01*
X1969178Y521824D01*
X1969833Y520074D01*
Y511616D01*
G01X1983621Y523282D02*
Y511616D01*
G01Y527949D02*
X1983184Y528241D01*
Y528824D01*
X1983621Y529116D01*
X1984058Y528824D01*
Y528241D01*
X1983621Y527949D01*
G01X1997846Y513657D02*
X1998938Y512491D01*
X2000466Y511616D01*
X2001776D01*
X2003086Y512199D01*
X2003959Y513074D01*
X2004396Y514240D01*
X2004178Y515991D01*
X2003304Y516866D01*
X1999374Y518616D01*
X1998501Y520658D01*
X1998938Y522116D01*
X1999811Y522991D01*
X2001121Y523282D01*
X2002431Y522991D01*
X2003741Y522116D01*
G01X2033501Y529116D02*
X2038741D01*
G01X2036121D02*
Y511616D01*
G01X2033501D02*
X2038741D01*
G01X2047071D02*
Y523282D01*
G01Y520074D02*
X2047726Y521533D01*
X2048818Y522699D01*
X2050346Y523282D01*
X2051874Y522699D01*
X2052966Y521533D01*
X2053621Y520074D01*
Y511616D01*
G01Y520074D02*
X2054276Y521533D01*
X2055367Y522699D01*
X2056896Y523282D01*
X2058424Y522699D01*
X2059516Y521533D01*
X2060171Y519783D01*
Y511616D01*
G01X2067191Y505783D02*
Y523282D01*
G01Y520658D02*
X2068283Y522116D01*
X2069374Y522991D01*
X2071121Y523282D01*
X2072649Y522991D01*
X2074178Y521533D01*
X2074833Y519491D01*
X2075051Y517449D01*
X2074833Y515407D01*
X2074178Y513366D01*
X2072867Y512199D01*
X2071121Y511616D01*
X2069593Y511908D01*
X2068064Y512782D01*
X2067191Y513949D01*
G01X2085346Y519491D02*
X2092333D01*
X2091678Y521533D01*
X2090586Y522699D01*
X2089058Y523282D01*
X2087529Y522991D01*
X2086219Y522116D01*
X2085346Y520074D01*
X2084909Y518324D01*
Y516574D01*
X2085346Y514824D01*
X2086438Y513074D01*
X2087748Y511908D01*
X2089276Y511616D01*
X2090804Y512199D01*
X2092333Y513949D01*
G01X2110051Y529116D02*
Y511616D01*
G01Y514240D02*
X2109178Y512782D01*
X2107867Y511908D01*
X2106339Y511616D01*
X2104593Y512199D01*
X2103283Y513657D01*
X2102409Y515407D01*
X2102191Y517449D01*
X2102409Y519491D01*
X2103283Y521241D01*
X2104593Y522699D01*
X2106339Y523282D01*
X2107867Y522991D01*
X2108959Y522407D01*
X2110051Y521241D01*
G01X2127551Y511616D02*
Y523282D01*
G01Y521241D02*
X2126678Y522407D01*
X2125367Y522991D01*
X2123839Y523282D01*
X2122311Y522699D01*
X2121001Y521533D01*
X2120127Y519783D01*
X2119691Y517449D01*
X2120127Y515116D01*
X2121001Y513366D01*
X2122311Y512199D01*
X2123839Y511616D01*
X2125367Y511908D01*
X2126678Y512782D01*
X2127551Y513949D01*
G01X2137409Y511616D02*
Y523282D01*
G01Y520366D02*
X2138283Y521824D01*
X2139593Y522991D01*
X2141339Y523282D01*
X2142867Y522991D01*
X2144178Y521824D01*
X2144833Y519783D01*
Y511616D01*
G01X2162114Y521824D02*
X2160586Y522991D01*
X2159276Y523282D01*
X2157529Y522699D01*
X2156219Y521533D01*
X2155346Y519491D01*
X2155127Y517449D01*
X2155346Y515407D01*
X2156219Y513657D01*
X2157529Y512199D01*
X2159276Y511616D01*
X2160804Y512199D01*
X2162114Y513366D01*
G01X2172846Y519491D02*
X2179833D01*
X2179178Y521533D01*
X2178086Y522699D01*
X2176558Y523282D01*
X2175029Y522991D01*
X2173719Y522116D01*
X2172846Y520074D01*
X2172409Y518324D01*
Y516574D01*
X2172846Y514824D01*
X2173938Y513074D01*
X2175248Y511908D01*
X2176776Y511616D01*
X2178304Y512199D01*
X2179833Y513949D01*
G01X20103Y-86244D02*
G03I-4291J0D01*
G01X0Y-87362D02*
G03X15000Y-102362I15000J0D01*
G01X0Y-11811D02*
Y-87362D01*
G01X3937Y-7874D02*
G03X0Y-11811I0J-3937D01*
G01X15748Y-7874D02*
X3937D01*
G01X0Y7874D02*
G03X7874Y0I7874J0D01*
G01X818897D02*
X7874D01*
G01X0Y7874D02*
Y562992D01*
G01X7874Y570866D02*
G03X0Y562992I0J-7874D01*
G01X7874Y570866D02*
X326781D01*
G01X312004Y-102362D02*
X15000D01*
G01X46456Y0D02*
G03Y-7874I0J-3937D01*
G01X15748D02*
G03Y0I0J3937D01*
G01X287400Y-7874D02*
X46456D01*
G01X40452Y499724D02*
G03I-3051J0D01*
G01X41535Y535157D02*
G03I-4134J0D01*
G01X44685Y517441D02*
G03I-7284J0D01*
G01X121082Y39055D02*
G03I-5019J0D01*
G01X120807Y14567D02*
G03I-4744J0D01*
G01X319878Y-102362D02*
G03X312004I-3937J0D01*
G01X811771D02*
X319878D01*
G01X326770Y0D02*
G03Y-7874I0J-3937D01*
G01X287400D02*
G03Y0I0J3937D01*
G01X302165Y531496D02*
G03I-6890J0D01*
G01X597707Y-7874D02*
X326770D01*
G01X379921Y156220D02*
G03I-5906J0D01*
G01X342529Y530315D02*
G03X334655I-3937J0D01*
G01X342529Y520720D02*
G03X352474Y509057I11811J0D01*
G01X334655Y520720D02*
G03X351230Y501282I19685J0D01*
G01X384484Y503937D02*
X352475Y509057D01*
G01X383858Y496063D02*
X351231Y501282D01*
G01X442287Y503937D02*
X384484D01*
G01X442913Y496063D02*
X383858D01*
G01X342529Y530315D02*
Y520720D01*
G01X334655Y562992D02*
Y520720D01*
G01X346466Y570866D02*
G03X342529Y566929I0J-3937D01*
G01X334655Y555512D02*
G03X342529I3937J0D01*
G01X346466Y570866D02*
X480325D01*
G01X334655Y562992D02*
G03X326781Y570866I-7874J0D01*
G01X342529Y566929D02*
Y555512D01*
G01X415943Y539991D02*
G03I-4291J0D01*
G01X474316Y509060D02*
X442287Y503937D01*
G01X475560Y501285D02*
X442913Y496063D01*
G01X492136Y530315D02*
G03X484262I-3937J0D01*
G01X474316Y509060D02*
G03X484262Y520723I-1865J11663D01*
G01X475560Y501285D02*
G03X492136Y520723I-3109J19438D01*
G01X484262Y530315D02*
Y520723D01*
G01X492136Y562992D02*
Y520723D01*
G01X484262Y566929D02*
G03X480325Y570866I-3937J0D01*
G01X484262Y555512D02*
G03X492136I3937J0D01*
G01X500010Y570866D02*
G03X492136Y562992I0J-7874D01*
G01X500010Y570866D02*
X818897D01*
G01X484262Y566929D02*
Y555512D01*
G01X537401Y371299D02*
G03I-5905J0D01*
G01X538386Y531496D02*
G03I-6890J0D01*
G01X628416Y0D02*
G03Y-7874I0J-3937D01*
G01X597707D02*
G03Y0I0J3937D01*
G01X780315Y-7874D02*
X628416D01*
G01X602362Y116141D02*
G03I-5906J0D01*
G01X817003Y-86834D02*
G03I-4292J0D01*
G01X811771Y-102362D02*
G03X826771Y-87362I0J15000D01*
G01X811023Y0D02*
G03Y-7874I0J-3937D01*
G01X780315D02*
G03Y0I0J3937D01*
G01X822834Y-7874D02*
X811023D01*
G01X818897Y0D02*
G03X826771Y7874I0J7874D01*
G01X818897Y0D02*
X807086D01*
G01X787401Y198819D02*
G03I-5905J0D01*
G01X792421Y499724D02*
G03I-3051J0D01*
G01X793504Y535157D02*
G03I-4134J0D01*
G01X796653Y517441D02*
G03I-7283J0D01*
G01X826771Y562992D02*
G03X818897Y570866I-7874J0D01*
G01X826771Y-11811D02*
Y-87362D01*
G01Y-11811D02*
G03X822834Y-7874I-3937J0D01*
G01X826771Y562992D02*
Y7874D01*
G54D12*
G01X358018Y13792D02*
X359374D01*
G01X358018Y12192D02*
X359374D01*
G01X357100Y14710D02*
G03X358018Y13792I918J0D01*
G01X355500Y14710D02*
G03X358018Y12192I2518J0D01*
G01X357100Y64343D02*
Y14710D01*
G01X355500Y64512D02*
Y14710D01*
G01X358018Y12192D02*
X359374D01*
G01X358018Y13792D02*
X359374D01*
G01X355500Y14710D02*
G03X358018Y12192I2518J0D01*
G01X357100Y14710D02*
G03X358018Y13792I918J0D01*
G01X355500Y64512D02*
Y14710D01*
G01X357100Y64343D02*
Y14710D01*
G01X350013Y19139D02*
Y63451D01*
G01X348413Y19139D02*
Y63620D01*
G01X350635Y18517D02*
G02X350013Y19139I0J622D01*
G01X350635Y16917D02*
G02X348413Y19139I0J2222D01*
G01X352287Y18517D02*
X350635D01*
G01X352287Y16917D02*
X350635D01*
G01X348413Y19139D02*
Y63620D01*
G01X350013Y19139D02*
Y63451D01*
G01X350635Y16917D02*
G02X348413Y19139I0J2222D01*
G01X350635Y18517D02*
G02X350013Y19139I0J622D01*
G01X352287Y16917D02*
X350635D01*
G01X352287Y18517D02*
X350635D01*
G01X342927Y14710D02*
Y65466D01*
G01X341327Y65635D02*
Y14710D01*
G01X343845Y13792D02*
G02X342927Y14710I0J918D01*
G01X341327D02*
G03X343845Y12192I2518J0D01*
G01X345201Y13792D02*
X343845D01*
G01Y12192D02*
X345201D01*
G01X343845D02*
X345201D01*
G01Y13792D02*
X343845D01*
G01X341327Y14710D02*
G03X343845Y12192I2518J0D01*
G01Y13792D02*
G02X342927Y14710I0J918D01*
G01X341327Y65635D02*
Y14710D01*
G01X342927D02*
Y65466D01*
G01X335444Y19831D02*
Y68992D01*
G01X333844Y69164D02*
Y19831D01*
G01X336758Y18517D02*
G02X335444Y19831I0J1314D01*
G01X333844D02*
G03X336758Y16917I2914J0D01*
G01X338114Y18517D02*
X336758D01*
G01Y16917D02*
X338114D01*
G01X336758D02*
X338114D01*
G01Y18517D02*
X336758D01*
G01X333844Y19831D02*
G03X336758Y16917I2914J0D01*
G01Y18517D02*
G02X335444Y19831I0J1314D01*
G01X333844Y69164D02*
Y19831D01*
G01X335444D02*
Y68992D01*
G01X386364Y13792D02*
X387720D01*
G01X386364Y12192D02*
X387720D01*
G01X385446Y14710D02*
G03X386364Y13792I918J0D01*
G01X383846Y14710D02*
G03X386364Y12192I2518J0D01*
G01X385446Y48873D02*
Y14710D01*
G01X383846Y49042D02*
Y14710D01*
G01X387456Y58324D02*
X385446Y48873D01*
G01X385952Y58947D02*
X383846Y49042D01*
G01X386364Y12192D02*
X387720D01*
G01X386364Y13792D02*
X387720D01*
G01X383846Y14710D02*
G03X386364Y12192I2518J0D01*
G01X385446Y14710D02*
G03X386364Y13792I918J0D01*
G01X383846Y49042D02*
Y14710D01*
G01X385446Y48873D02*
Y14710D01*
G01X385952Y58947D02*
X383846Y49042D01*
G01X387456Y58324D02*
X385446Y48873D01*
G01X379278Y18517D02*
X380634D01*
G01X379278Y16917D02*
X380634D01*
G01X378341Y19454D02*
G03X379278Y18517I937J0D01*
G01X376741Y19454D02*
G03X379278Y16917I2537J0D01*
G01X378341Y51346D02*
Y19454D01*
G01X376741Y51515D02*
Y19454D01*
G01X379278Y16917D02*
X380634D01*
G01X379278Y18517D02*
X380634D01*
G01X376741Y19454D02*
G03X379278Y16917I2537J0D01*
G01X378341Y19454D02*
G03X379278Y18517I937J0D01*
G01X376741Y51515D02*
Y19454D01*
G01X378341Y51346D02*
Y19454D01*
G01X372191Y13792D02*
X373547D01*
G01X372191Y12192D02*
X373547D01*
G01X371273Y14710D02*
G03X372191Y13792I918J0D01*
G01X369673Y14710D02*
G03X372191Y12192I2518J0D01*
G01X371273Y50679D02*
Y14710D01*
G01X369673Y50848D02*
Y14710D01*
G01X373552Y61410D02*
X371273Y50679D01*
G01X372048Y62033D02*
X369673Y50848D01*
G01X372191Y12192D02*
X373547D01*
G01X372191Y13792D02*
X373547D01*
G01X369673Y14710D02*
G03X372191Y12192I2518J0D01*
G01X371273Y14710D02*
G03X372191Y13792I918J0D01*
G01X369673Y50848D02*
Y14710D01*
G01X371273Y50679D02*
Y14710D01*
G01X372048Y62033D02*
X369673Y50848D01*
G01X373552Y61410D02*
X371273Y50679D01*
G01X365104Y18517D02*
X366460D01*
G01X365104Y16917D02*
X366460D01*
G01X364186Y19435D02*
G03X365104Y18517I918J0D01*
G01X362586Y19435D02*
G03X365104Y16917I2518J0D01*
G01X364186Y52310D02*
Y19435D01*
G01X362586Y52478D02*
Y19435D01*
G01X365104Y16917D02*
X366460D01*
G01X365104Y18517D02*
X366460D01*
G01X362586Y19435D02*
G03X365104Y16917I2518J0D01*
G01X364186Y19435D02*
G03X365104Y18517I918J0D01*
G01X362586Y52478D02*
Y19435D01*
G01X364186Y52310D02*
Y19435D01*
G01X362064Y87696D02*
X357100Y64343D01*
G01X365317Y110699D02*
X355500Y64512D01*
G01X363116Y92646D02*
X362810Y91208D01*
G01X365317Y110699D02*
X355500Y64512D01*
G01X364168Y97595D02*
X363862Y96157D01*
G01X365317Y110699D02*
X355500Y64512D01*
G01X365220Y102544D02*
X364914Y101106D01*
G01X365317Y110699D02*
X355500Y64512D01*
G01X366953Y110699D02*
X365966Y106056D01*
G01X365317Y110699D02*
X355500Y64512D01*
G01X357736Y154098D02*
X366953Y110699D01*
G01X356100Y154098D02*
X365317Y110699D01*
G01D02*
X355500Y64512D01*
G01X362064Y87696D02*
X357100Y64343D01*
G01X363116Y92646D02*
X362810Y91208D01*
G01X364168Y97595D02*
X363862Y96157D01*
G01X365220Y102544D02*
X364914Y101106D01*
G01X366953Y110699D02*
X365966Y106056D01*
G01X356100Y154098D02*
X365317Y110699D01*
G01X357736Y154098D02*
X366953Y110699D01*
G01X359835Y109662D02*
X350541Y153386D01*
G01X358199Y109662D02*
X348905Y153386D01*
G01X358301Y102445D02*
X359835Y109662D01*
G01X348413Y63620D02*
X358199Y109662D01*
G01X357249Y97495D02*
X357555Y98933D01*
G01X348413Y63620D02*
X358199Y109662D01*
G01X356197Y92546D02*
X356503Y93984D01*
G01X348413Y63620D02*
X358199Y109662D01*
G01X355145Y87597D02*
X355451Y89035D01*
G01X348413Y63620D02*
X358199Y109662D01*
G01X350013Y63451D02*
X354399Y84085D01*
G01X348413Y63620D02*
X358199Y109662D01*
G01D02*
X348905Y153386D01*
G01X359835Y109662D02*
X350541Y153386D01*
G01X348413Y63620D02*
X358199Y109662D01*
G01X358301Y102445D02*
X359835Y109662D01*
G01X357249Y97495D02*
X357555Y98933D01*
G01X356197Y92546D02*
X356503Y93984D01*
G01X355145Y87597D02*
X355451Y89035D01*
G01X350013Y63451D02*
X354399Y84085D01*
G01X352654Y111229D02*
X343639Y153649D01*
G01X342003D02*
X351018Y111229D01*
G01X351689Y106690D02*
X352654Y111229D01*
G01X351018D02*
X341327Y65635D01*
G01X350637Y101740D02*
X350943Y103178D01*
G01X351018Y111229D02*
X341327Y65635D01*
G01X349585Y96791D02*
X349891Y98229D01*
G01X351018Y111229D02*
X341327Y65635D01*
G01X348533Y91841D02*
X348839Y93279D01*
G01X351018Y111229D02*
X341327Y65635D01*
G01X342927Y65466D02*
X347787Y88330D01*
G01X351018Y111229D02*
X341327Y65635D01*
G01X351018Y111229D02*
X341327Y65635D01*
G01X351689Y106690D02*
X352654Y111229D01*
G01X350637Y101740D02*
X350943Y103178D01*
G01X349585Y96791D02*
X349891Y98229D01*
G01X348533Y91841D02*
X348839Y93279D01*
G01X342927Y65466D02*
X347787Y88330D01*
G01X342003Y153649D02*
X351018Y111229D01*
G01X352654D02*
X343639Y153649D01*
G01X343847Y116235D02*
X333844Y69164D01*
G01X335444Y68992D02*
X345413Y115902D01*
G01X343847Y116235D02*
X333844Y69164D01*
G01X343847Y116235D02*
X333844Y69164D01*
G01X335444Y68992D02*
X345413Y115902D01*
G01X392088Y68392D02*
X385952Y58947D01*
G01X392088Y68392D02*
X385952Y58947D01*
G01X379617Y57345D02*
X378341Y51346D01*
G01X378113Y57968D02*
X376741Y51515D01*
G01X388666Y71278D02*
X379617Y57345D01*
G01X387162Y71901D02*
X378113Y57968D01*
G01D02*
X376741Y51515D01*
G01X379617Y57345D02*
X378341Y51346D01*
G01X387162Y71901D02*
X378113Y57968D01*
G01X388666Y71278D02*
X379617Y57345D01*
G01X376773Y66370D02*
X373552Y61410D01*
G01X382737Y78496D02*
X372048Y62033D01*
G01X379529Y70614D02*
X378728Y69381D01*
G01X382737Y78496D02*
X372048Y62033D01*
G01X382285Y74857D02*
X381484Y73625D01*
G01X382737Y78496D02*
X372048Y62033D01*
G01X390899Y109192D02*
X384240Y77868D01*
G01X395928Y140554D02*
X382737Y78496D01*
G01X395928Y140554D02*
X382737Y78496D01*
G01D02*
X372048Y62033D01*
G01X376773Y66370D02*
X373552Y61410D01*
G01X379529Y70614D02*
X378728Y69381D01*
G01X382285Y74857D02*
X381484Y73625D01*
G01X395928Y140554D02*
X382737Y78496D01*
G01X390899Y109192D02*
X384240Y77868D01*
G01X367490Y67869D02*
X364186Y52310D01*
G01X365986Y68492D02*
X362586Y52478D01*
G01X372885Y76175D02*
X367490Y67869D01*
G01X379650Y89530D02*
X365986Y68492D01*
G01X375641Y80418D02*
X374841Y79185D01*
G01X379650Y89530D02*
X365986Y68492D01*
G01X378398Y84662D02*
X377597Y83429D01*
G01X379650Y89530D02*
X365986Y68492D01*
G01X381154Y88907D02*
X380353Y87672D01*
G01X379650Y89530D02*
X365986Y68492D01*
G01X386752Y115245D02*
X381154Y88907D01*
G01X390722Y141623D02*
X379650Y89530D01*
G01X390722Y141623D02*
X379650Y89530D01*
G01X365986Y68492D02*
X362586Y52478D01*
G01X367490Y67869D02*
X364186Y52310D01*
G01X379650Y89530D02*
X365986Y68492D01*
G01X372885Y76175D02*
X367490Y67869D01*
G01X375641Y80418D02*
X374841Y79185D01*
G01X378398Y84662D02*
X377597Y83429D01*
G01X381154Y88907D02*
X380353Y87672D01*
G01X390722Y141623D02*
X379650Y89530D01*
G01X386752Y115245D02*
X381154Y88907D01*
G01X362280Y175486D02*
X357736Y154098D01*
G01X360776Y176109D02*
X356100Y154098D01*
G01X364784Y179345D02*
X362280Y175486D01*
G01X360776Y176109D02*
X356100Y154098D01*
G01X362280Y175486D02*
X357736Y154098D01*
G01X364784Y179345D02*
X362280Y175486D01*
G01X353864Y161236D02*
X359898Y189601D01*
G01X352360Y161859D02*
X358333Y189934D01*
G01X351403Y157448D02*
X353864Y161236D01*
G01X349899Y158071D02*
X352360Y161859D01*
G01X350541Y153386D02*
X351403Y157448D01*
G01X348905Y153386D02*
X349899Y158071D01*
G01X353864Y161236D02*
X359898Y189601D01*
G01X352360Y161859D02*
X358333Y189934D01*
G01X353864Y161236D02*
X359898Y189601D01*
G01X349899Y158071D02*
X352360Y161859D01*
G01X351403Y157448D02*
X353864Y161236D01*
G01X348905Y153386D02*
X349899Y158071D01*
G01X350541Y153386D02*
X351403Y157448D01*
G01X345744Y163548D02*
X350516Y185986D01*
G01X349012Y186609D02*
X342003Y153649D01*
G01X344692Y158598D02*
X344997Y160036D01*
G01X349012Y186609D02*
X342003Y153649D01*
G01X343639D02*
X343945Y155087D01*
G01X349012Y186609D02*
X342003Y153649D01*
G01X349012Y186609D02*
X342003Y153649D01*
G01X345744Y163548D02*
X350516Y185986D01*
G01X344692Y158598D02*
X344997Y160036D01*
G01X343639Y153649D02*
X343945Y155087D01*
G01X343542Y189136D02*
X335947Y153396D01*
G01X343542Y189136D02*
X335947Y153396D01*
G01X343542Y189136D02*
X335947Y153396D01*
G01X341487Y171768D02*
X341793Y173206D01*
G01X343542Y189136D02*
X335947Y153396D01*
G01X337583D02*
X340741Y168257D01*
G01X343542Y189136D02*
X335947Y153396D01*
G01X345484Y116235D02*
X337583Y153396D01*
G01X335947D02*
X343848Y116235D01*
G01X345414Y115902D02*
X345484Y116235D01*
G01X345414Y115902D02*
X345484Y116235D01*
G01X335947Y153396D02*
X343848Y116235D01*
G01X345484D02*
X337583Y153396D01*
G01X343542Y189136D02*
X335947Y153396D01*
G01X341487Y171768D02*
X341793Y173206D01*
G01X337583Y153396D02*
X340741Y168257D01*
G01X386838Y169890D02*
X391077Y163364D01*
G01X386838Y169890D02*
X391077Y163364D01*
G01X392358Y141623D02*
X386752Y115245D01*
G01X386478Y161590D02*
X390722Y141623D01*
G01X382430Y170763D02*
X387982Y162213D01*
G01X380830Y170289D02*
X386478Y161590D01*
G01X382430Y172730D02*
Y170763D01*
G01X380830Y172670D02*
Y170289D01*
G01X392358Y141623D02*
X386752Y115245D01*
G01X386478Y161590D02*
X390722Y141623D01*
G01X380830Y170289D02*
X386478Y161590D01*
G01X382430Y170763D02*
X387982Y162213D01*
G01X380830Y172670D02*
Y170289D01*
G01X382430Y172730D02*
Y170763D01*
G01X386754Y189845D02*
X391825Y194916D01*
G01X386754Y176946D02*
Y189845D01*
G01Y176946D02*
Y189845D01*
G01Y176946D02*
Y189845D01*
G01X384416Y198642D02*
X387817Y202043D01*
G01X383753Y200242D02*
X387154Y203643D01*
G01X382803Y200242D02*
X383753D01*
G01X382803Y198642D02*
X384416D01*
G01X382803Y200242D02*
X383753D01*
G01D02*
X387154Y203643D01*
G01X384416Y198642D02*
X387817Y202043D01*
G01X382803Y200242D02*
X383753D01*
G01X384416Y198642D02*
X387817Y202043D01*
G01X382803Y198642D02*
X384416D01*
G01X384464Y204042D02*
X382703D01*
G01X382903Y205642D02*
X383801D01*
G01X386385Y205963D02*
X384464Y204042D01*
G01X383801Y205642D02*
X385722Y207563D01*
G01X387893Y205963D02*
X386385D01*
G01X385722Y207563D02*
X387893D01*
G01X385722D02*
X387893D01*
G01Y205963D02*
X386385D01*
G01X383801Y205642D02*
X385722Y207563D01*
G01X386385Y205963D02*
X384464Y204042D01*
G01X382903Y205642D02*
X383801D01*
G01X384464Y204042D02*
X382703D01*
G01X384603Y209831D02*
X388424D01*
G01X383940Y211431D02*
X388424D01*
G01X382700Y209539D02*
X384311D01*
G01X382906Y211139D02*
X383648D01*
G01X383940Y211431D02*
X388424D01*
G01X384603Y209831D02*
X388424D01*
G01X382906Y211139D02*
X383648D01*
G01X382700Y209539D02*
X384311D01*
G01X385197Y215135D02*
X382796D01*
G01X385860Y216735D02*
X382810D01*
G01X386564Y213768D02*
X385197Y215135D01*
G01X387227Y215368D02*
X385860Y216735D01*
G01X389238Y213768D02*
X386564D01*
G01X385860Y216735D02*
X382810D01*
G01X385197Y215135D02*
X382796D01*
G01X387227Y215368D02*
X385860Y216735D01*
G01X386564Y213768D02*
X385197Y215135D01*
G01X389238Y213768D02*
X386564D01*
G01X386754Y189845D02*
X391825Y194916D01*
G01X386754Y176946D02*
Y189845D01*
G01X385978Y194242D02*
X389662Y197926D01*
G01X380893Y191420D02*
X388999Y199526D01*
G01X382493Y190757D02*
X383439Y191703D01*
G01X380893Y191420D02*
X388999Y199526D01*
G01X382493Y186674D02*
Y190757D01*
G01X380893Y176393D02*
Y191420D01*
G01X382493Y181614D02*
Y183084D01*
G01X380893Y176393D02*
Y191420D01*
G01X382493Y176307D02*
Y178024D01*
G01X380893Y176393D02*
Y191420D01*
G01D02*
X388999Y199526D01*
G01X385978Y194242D02*
X389662Y197926D01*
G01X382493Y190757D02*
X383439Y191703D01*
G01X380893Y176393D02*
Y191420D01*
G01X382493Y186674D02*
Y190757D01*
G01Y181614D02*
Y183084D01*
G01Y176307D02*
Y178024D01*
G01X373874Y196295D02*
X360776Y176109D01*
G01X367289Y183205D02*
X364784Y179345D01*
G01X373874Y196295D02*
X360776Y176109D01*
G01X370043Y187450D02*
X369243Y186217D01*
G01X373874Y196295D02*
X360776Y176109D01*
G01X373607Y192944D02*
X371997Y190462D01*
G01X373874Y196295D02*
X360776Y176109D01*
G01X374411Y194183D02*
X373607Y192944D01*
G01X373874Y196295D02*
X360776Y176109D01*
G01X375474Y195821D02*
X374411Y194183D01*
G01X373874Y196295D02*
X360776Y176109D01*
G01X375474Y197993D02*
Y195821D01*
G01X373874Y198656D02*
Y196295D01*
G01X375942Y198461D02*
X375474Y197993D01*
G01X375279Y200061D02*
X373874Y198656D01*
G01X377200Y198461D02*
X375942D01*
G01X375279Y200061D02*
X373874Y198656D01*
G01X377170Y200061D02*
X375279D01*
G01X373874Y196295D02*
X360776Y176109D01*
G01X367289Y183205D02*
X364784Y179345D01*
G01X370043Y187450D02*
X369243Y186217D01*
G01X373607Y192944D02*
X371997Y190462D01*
G01X374411Y194183D02*
X373607Y192944D01*
G01X375474Y195821D02*
X374411Y194183D01*
G01X373874Y198656D02*
Y196295D01*
G01X375474Y197993D02*
Y195821D01*
G01X375279Y200061D02*
X373874Y198656D01*
G01X375942Y198461D02*
X375474Y197993D01*
G01X377200Y198461D02*
X375942D01*
G01X377170Y200061D02*
X375279D01*
G01X377200Y198461D02*
X375942D01*
G01X373752Y203992D02*
X377119D01*
G01X373278Y205592D02*
X376919D01*
G01X365974Y198940D02*
X373752Y203992D01*
G01X364817Y200098D02*
X373278Y205592D01*
G01X365486Y198190D02*
X365974Y198940D01*
G01X364145Y199063D02*
X364817Y200098D01*
G01X358394Y190225D02*
X364144Y199064D01*
G01X362726Y193949D02*
X363528Y195181D01*
G01X358394Y190225D02*
X364144Y199064D01*
G01X359898Y189601D02*
X360769Y190940D01*
G01X358394Y190225D02*
X364144Y199064D01*
G01X358332Y189934D02*
X358394Y190225D01*
G01X373278Y205592D02*
X376919D01*
G01X373752Y203992D02*
X377119D01*
G01X364817Y200098D02*
X373278Y205592D01*
G01X365974Y198940D02*
X373752Y203992D01*
G01X364145Y199063D02*
X364817Y200098D01*
G01X365486Y198190D02*
X365974Y198940D01*
G01X358394Y190225D02*
X364144Y199064D01*
G01X365486Y198190D02*
X365974Y198940D01*
G01X362726Y193949D02*
X363528Y195181D01*
G01X359898Y189601D02*
X360769Y190940D01*
G01X358332Y189934D02*
X358394Y190225D01*
G01X374715Y209492D02*
X377119D01*
G01X376919Y211092D02*
X374547D01*
G01X371944Y208904D02*
X374715Y209492D01*
G01X374547Y211092D02*
X371322Y210408D01*
G01X360625Y201553D02*
X371944Y208904D01*
G01X371322Y210408D02*
X359468Y202710D01*
G01X350516Y185986D02*
X360625Y201553D01*
G01X359468Y202710D02*
X349012Y186609D01*
G01X359468Y202710D02*
X349012Y186609D01*
G01X350516Y185986D02*
X360625Y201553D01*
G01X371322Y210408D02*
X359468Y202710D01*
G01X360625Y201553D02*
X371944Y208904D01*
G01X374547Y211092D02*
X371322Y210408D01*
G01X371944Y208904D02*
X374715Y209492D01*
G01X376919Y211092D02*
X374547D01*
G01X374715Y209492D02*
X377119D01*
G01X374402Y214979D02*
X377182D01*
G01X376856Y216579D02*
X374233D01*
G01X367498Y213510D02*
X374402Y214979D01*
G01X374233Y216579D02*
X366875Y215014D01*
G01X356742Y206526D02*
X367498Y213510D01*
G01X366875Y215014D02*
X355585Y207683D01*
G01X355624Y204804D02*
X356742Y206526D01*
G01X355585Y207683D02*
X343542Y189136D01*
G01X354545Y203142D02*
X355624Y204803D01*
G01X355585Y207683D02*
X343542Y189136D01*
G01X351789Y198898D02*
X352590Y200131D01*
G01X355585Y207683D02*
X343542Y189136D01*
G01X345046Y188513D02*
X349834Y195887D01*
G01X355585Y207683D02*
X343542Y189136D01*
G01X344643Y186617D02*
X345046Y188513D01*
G01X343591Y181668D02*
X343897Y183106D01*
G01X342539Y176718D02*
X342845Y178156D01*
G01X344643Y186617D02*
X345046Y188513D01*
G01X343591Y181668D02*
X343897Y183106D01*
G01X342539Y176718D02*
X342845Y178156D01*
G01X355585Y207683D02*
X343542Y189136D01*
G01X355624Y204804D02*
X356742Y206526D01*
G01X354545Y203142D02*
X355624Y204803D01*
G01X351789Y198898D02*
X352590Y200131D01*
G01X345046Y188513D02*
X349834Y195887D01*
G01X366875Y215014D02*
X355585Y207683D01*
G01X356742Y206526D02*
X367498Y213510D01*
G01X374233Y216579D02*
X366875Y215014D01*
G01X367498Y213510D02*
X374402Y214979D01*
G01X376856Y216579D02*
X374233D01*
G01X374402Y214979D02*
X377182D01*
G01X447626Y19435D02*
G03X450144Y16917I2518J0D01*
G01X447626Y69615D02*
Y19435D01*
G01D02*
G03X450144Y16917I2518J0D01*
G01X447626Y69615D02*
Y19435D01*
G01X443057Y13792D02*
X444413D01*
G01X443057Y12192D02*
X444413D01*
G01X442139Y14710D02*
G03X443057Y13792I918J0D01*
G01X440539Y14710D02*
G03X443057Y12192I2518J0D01*
G01X442139Y64322D02*
Y14710D01*
G01X440539Y64491D02*
Y14710D01*
G01X443057Y12192D02*
X444413D01*
G01X443057Y13792D02*
X444413D01*
G01X440539Y14710D02*
G03X443057Y12192I2518J0D01*
G01X442139Y14710D02*
G03X443057Y13792I918J0D01*
G01X440539Y64491D02*
Y14710D01*
G01X442139Y64322D02*
Y14710D01*
G01X435053Y19435D02*
Y60606D01*
G01X433453Y60775D02*
Y19435D01*
G01X435971Y18517D02*
G02X435053Y19435I0J918D01*
G01X433453D02*
G03X435971Y16917I2518J0D01*
G01X437327Y18517D02*
X435971D01*
G01Y16917D02*
X437327D01*
G01X435971D02*
X437327D01*
G01Y18517D02*
X435971D01*
G01X433453Y19435D02*
G03X435971Y16917I2518J0D01*
G01Y18517D02*
G02X435053Y19435I0J918D01*
G01X433453Y60775D02*
Y19435D01*
G01X435053D02*
Y60606D01*
G01X428884Y13792D02*
X430240D01*
G01X428884Y12192D02*
X430240D01*
G01X427966Y14710D02*
G03X428884Y13792I918J0D01*
G01X426366Y14710D02*
G03X428884Y12192I2518J0D01*
G01X427966Y55537D02*
Y14710D01*
G01X426366Y55706D02*
Y14710D01*
G01X428884Y12192D02*
X430240D01*
G01X428884Y13792D02*
X430240D01*
G01X426366Y14710D02*
G03X428884Y12192I2518J0D01*
G01X427966Y14710D02*
G03X428884Y13792I918J0D01*
G01X426366Y55706D02*
Y14710D01*
G01X427966Y55537D02*
Y14710D01*
G01X421797Y18517D02*
X423153D01*
G01X421797Y16917D02*
X423153D01*
G01X420879Y19435D02*
G03X421797Y18517I918J0D01*
G01X419279Y19435D02*
G03X421797Y16917I2518J0D01*
G01X420879Y53145D02*
Y19435D01*
G01X419279Y53314D02*
Y19435D01*
G01X421797Y16917D02*
X423153D01*
G01X421797Y18517D02*
X423153D01*
G01X419279Y19435D02*
G03X421797Y16917I2518J0D01*
G01X420879Y19435D02*
G03X421797Y18517I918J0D01*
G01X419279Y53314D02*
Y19435D01*
G01X420879Y53145D02*
Y19435D01*
G01X430303Y133603D02*
X412193Y48434D01*
G01X430303Y133603D02*
X412193Y48434D01*
G01X430303Y133603D02*
X412193Y48434D01*
G01X413793Y48265D02*
X427866Y114446D01*
G01X430303Y133603D02*
X412193Y48434D01*
G01X413793Y14710D02*
Y48265D01*
G01X412193Y48434D02*
Y14710D01*
G01X414711Y13792D02*
G02X413793Y14710I0J918D01*
G01X412193D02*
G03X414711Y12192I2518J0D01*
G01X416067Y13792D02*
X414711D01*
G01Y12192D02*
X416067D01*
G01X414711D02*
X416067D01*
G01Y13792D02*
X414711D01*
G01X412193Y14710D02*
G03X414711Y12192I2518J0D01*
G01Y13792D02*
G02X413793Y14710I0J918D01*
G01X412193Y48434D02*
Y14710D01*
G01X413793D02*
Y48265D01*
G01X430303Y133603D02*
X412193Y48434D01*
G01X413793Y48265D02*
X427866Y114446D01*
G01X407624Y18517D02*
X408980D01*
G01X407624Y16917D02*
X408980D01*
G01X406706Y19435D02*
G03X407624Y18517I918J0D01*
G01X405106Y19435D02*
G03X407624Y16917I2518J0D01*
G01X406706Y51187D02*
Y19435D01*
G01X405106Y51351D02*
Y19435D01*
G01X407453Y54802D02*
X406706Y51187D01*
G01X407624Y16917D02*
X408980D01*
G01X407624Y18517D02*
X408980D01*
G01X405106Y19435D02*
G03X407624Y16917I2518J0D01*
G01X406706Y19435D02*
G03X407624Y18517I918J0D01*
G01X405106Y51351D02*
Y19435D01*
G01X406706Y51187D02*
Y19435D01*
G01X407453Y54802D02*
X406706Y51187D01*
G01X407453Y54802D02*
X406706Y51187D01*
G01X407453Y54802D02*
X406706Y51187D01*
G01X399620Y48857D02*
X400867Y54724D01*
G01X398020Y49026D02*
X399363Y55347D01*
G01X399620Y14710D02*
Y48857D01*
G01X398020Y14710D02*
Y49026D01*
G01X400538Y13792D02*
G02X399620Y14710I0J918D01*
G01X400538Y12192D02*
G02X398020Y14710I0J2518D01*
G01X401894Y13792D02*
X400538D01*
G01X401894Y12192D02*
X400538D01*
G01X398020Y49026D02*
X399363Y55347D01*
G01X399620Y48857D02*
X400867Y54724D01*
G01X398020Y14710D02*
Y49026D01*
G01X399620Y14710D02*
Y48857D01*
G01X400538Y12192D02*
G02X398020Y14710I0J2518D01*
G01X400538Y13792D02*
G02X399620Y14710I0J918D01*
G01X401894Y12192D02*
X400538D01*
G01X401894Y13792D02*
X400538D01*
G01X393451Y18517D02*
X394807D01*
G01X393451Y16917D02*
X394807D01*
G01X392533Y19435D02*
G03X393451Y18517I918J0D01*
G01X390933Y19435D02*
G03X393451Y16917I2518J0D01*
G01X392533Y52724D02*
Y19435D01*
G01X390933Y52893D02*
Y19435D01*
G01X393451Y16917D02*
X394807D01*
G01X393451Y18517D02*
X394807D01*
G01X390933Y19435D02*
G03X393451Y16917I2518J0D01*
G01X392533Y19435D02*
G03X393451Y18517I918J0D01*
G01X390933Y52893D02*
Y19435D01*
G01X392533Y52724D02*
Y19435D01*
G01X459366Y124870D02*
X447626Y69615D01*
G01X459366Y124870D02*
X447626Y69615D01*
G01X459366Y124870D02*
X447626Y69615D01*
G01X459366Y124870D02*
X447626Y69615D01*
G01X459366Y124870D02*
X447626Y69615D01*
G01X451567Y108679D02*
X442139Y64322D01*
G01X452852Y122424D02*
X440539Y64491D01*
G01X452852Y122424D02*
X440539Y64491D01*
G01X452852Y122424D02*
X440539Y64491D01*
G01X452852Y122424D02*
X440539Y64491D01*
G01X451567Y108679D02*
X442139Y64322D01*
G01X447649Y127565D02*
X433453Y60775D01*
G01X447649Y127565D02*
X433453Y60775D01*
G01X447649Y127565D02*
X433453Y60775D01*
G01X435053Y60606D02*
X445861Y111455D01*
G01X447649Y127565D02*
X433453Y60775D01*
G01X447649Y127565D02*
X433453Y60775D01*
G01X435053Y60606D02*
X445861Y111455D01*
G01X440010Y112212D02*
X427966Y55537D01*
G01X442066Y129585D02*
X426366Y55706D01*
G01X442066Y129585D02*
X426366Y55706D01*
G01X442066Y129585D02*
X426366Y55706D01*
G01X442066Y129585D02*
X426366Y55706D01*
G01X442066Y129585D02*
X426366Y55706D01*
G01X440010Y112212D02*
X427966Y55537D01*
G01X433460Y112357D02*
X420879Y53145D01*
G01X435885Y131470D02*
X419279Y53314D01*
G01X435885Y131470D02*
X419279Y53314D01*
G01X435885Y131470D02*
X419279Y53314D01*
G01X435885Y131470D02*
X419279Y53314D01*
G01X435885Y131470D02*
X419279Y53314D01*
G01X433460Y112357D02*
X420879Y53145D01*
G01X405512Y53318D02*
X405106Y51351D01*
G01X405886Y55126D02*
X405512Y53318D01*
G01X405947Y55421D02*
X405886Y55126D01*
G01X409916Y58592D02*
X407453Y54802D01*
G01X408412Y59215D02*
X405947Y55421D01*
G01X423136Y120784D02*
X409916Y58592D01*
G01X414991Y90166D02*
X408412Y59215D01*
G01X424420Y134525D02*
X414991Y90166D01*
G01X424420Y134525D02*
X414991Y90166D01*
G01X424420Y134525D02*
X414991Y90166D01*
G01X405512Y53318D02*
X405106Y51351D01*
G01X405886Y55126D02*
X405512Y53318D01*
G01X405947Y55421D02*
X405886Y55126D01*
G01X408412Y59215D02*
X405947Y55421D01*
G01X409916Y58592D02*
X407453Y54802D01*
G01X414991Y90166D02*
X408412Y59215D01*
G01X423136Y120784D02*
X409916Y58592D01*
G01X424420Y134525D02*
X414991Y90166D01*
G01X423136Y120784D02*
X409916Y58592D01*
G01X402509Y60192D02*
X418937Y137478D01*
G01X402509Y60192D02*
X418937Y137478D01*
G01X402509Y60192D02*
X418937Y137478D01*
G01X404013Y59569D02*
X417013Y120730D01*
G01X402509Y60192D02*
X418937Y137478D01*
G01X400867Y54724D02*
X404013Y59569D01*
G01X399363Y55347D02*
X402509Y60192D01*
G01D02*
X418937Y137478D01*
G01X404013Y59569D02*
X417013Y120730D01*
G01X399363Y55347D02*
X402509Y60192D01*
G01X400867Y54724D02*
X404013Y59569D01*
G01X393216Y55935D02*
X392533Y52724D01*
G01X391712Y56558D02*
X390933Y52893D01*
G01X399121Y65028D02*
X393216Y55935D01*
G01X397617Y65651D02*
X391712Y56558D01*
G01X410422Y118205D02*
X399121Y65028D01*
G01X413397Y139905D02*
X397617Y65651D01*
G01X413397Y139905D02*
X397617Y65651D01*
G01X413397Y139905D02*
X397617Y65651D01*
G01X413397Y139905D02*
X397617Y65651D01*
G01X413397Y139905D02*
X397617Y65651D01*
G01X391712Y56558D02*
X390933Y52893D01*
G01X393216Y55935D02*
X392533Y52724D01*
G01X397617Y65651D02*
X391712Y56558D01*
G01X399121Y65028D02*
X393216Y55935D01*
G01X413397Y139905D02*
X397617Y65651D01*
G01X410422Y118205D02*
X399121Y65028D01*
G01X393592Y67769D02*
X387456Y58324D01*
G01X405020Y121550D02*
X393592Y67769D01*
G01X407682Y141777D02*
X392088Y68392D01*
G01X407682Y141777D02*
X392088Y68392D01*
G01X407682Y141777D02*
X392088Y68392D01*
G01X407682Y141777D02*
X392088Y68392D01*
G01X407682Y141777D02*
X392088Y68392D01*
G01X393592Y67769D02*
X387456Y58324D01*
G01X407682Y141777D02*
X392088Y68392D01*
G01X405020Y121550D02*
X393592Y67769D01*
G01X403458Y140881D02*
X388666Y71278D01*
G01X401822Y140881D02*
X387162Y71901D01*
G01X401822Y140881D02*
X387162Y71901D01*
G01X403458Y140881D02*
X388666Y71278D01*
G01X397564Y140554D02*
X390898Y109192D01*
G01X397564Y140554D02*
X390898Y109192D01*
G01X448351Y155535D02*
X454938Y124541D01*
G01X446751Y155366D02*
X453302Y124541D01*
G01X448351Y172651D02*
Y155535D01*
G01X446751Y172749D02*
Y155366D01*
G01D02*
X453302Y124541D01*
G01X448351Y155535D02*
X454938Y124541D01*
G01X446751Y172749D02*
Y155366D01*
G01X448351Y172651D02*
Y155535D01*
G01X442388Y160016D02*
Y172688D01*
G01X440788Y172712D02*
Y159847D01*
G01X449285Y127564D02*
X442388Y160016D01*
G01X440788Y159847D02*
X447649Y127565D01*
G01X448711Y124864D02*
X449285Y127564D01*
G01X447659Y119915D02*
X447965Y121353D01*
G01X446607Y114966D02*
X446913Y116404D01*
G01X448711Y124864D02*
X449285Y127564D01*
G01X447659Y119915D02*
X447965Y121353D01*
G01X446607Y114966D02*
X446913Y116404D01*
G01X440788Y159847D02*
X447649Y127565D01*
G01X449285Y127564D02*
X442388Y160016D01*
G01X440788Y172712D02*
Y159847D01*
G01X442388Y160016D02*
Y172688D01*
G01X441062Y117161D02*
X440756Y115723D01*
G01X442114Y122110D02*
X441808Y120673D01*
G01X443702Y129585D02*
X442862Y125632D01*
G01X436352Y164161D02*
X443702Y129585D01*
G01X434752Y163992D02*
X442066Y129585D01*
G01X436352Y172652D02*
Y164161D01*
G01X434752Y172748D02*
Y163992D01*
G01X441062Y117161D02*
X440756Y115723D01*
G01X442114Y122110D02*
X441808Y120673D01*
G01X443702Y129585D02*
X442862Y125632D01*
G01X434752Y163992D02*
X442066Y129585D01*
G01X436352Y164161D02*
X443702Y129585D01*
G01X434752Y172748D02*
Y163992D01*
G01X436352Y172652D02*
Y164161D01*
G01X434512Y117307D02*
X434206Y115869D01*
G01X435564Y122257D02*
X435258Y120819D01*
G01X437521Y131470D02*
X436310Y125769D01*
G01X430358Y165171D02*
X437521Y131470D01*
G01X428757Y165003D02*
X435885Y131470D01*
G01X430357Y172657D02*
Y165171D01*
G01X428757Y172743D02*
Y165003D01*
G01X434512Y117307D02*
X434206Y115869D01*
G01X435564Y122257D02*
X435258Y120819D01*
G01X437521Y131470D02*
X436310Y125769D01*
G01X428757Y165003D02*
X435885Y131470D01*
G01X430358Y165171D02*
X437521Y131470D01*
G01X428757Y172743D02*
Y165003D01*
G01X430357Y172657D02*
Y165171D01*
G01X424446Y168864D02*
Y172746D01*
G01X422846Y172654D02*
Y168695D01*
G01X431939Y133602D02*
X424446Y168864D01*
G01X422846Y168695D02*
X430303Y133603D01*
G01X430717Y127856D02*
X431939Y133602D01*
G01X429665Y122907D02*
X429971Y124345D01*
G01X428612Y117957D02*
X428918Y119395D01*
G01X430717Y127856D02*
X431939Y133602D01*
G01X429665Y122907D02*
X429971Y124345D01*
G01X428612Y117957D02*
X428918Y119395D01*
G01X422846Y168695D02*
X430303Y133603D01*
G01X431939Y133602D02*
X424446Y168864D01*
G01X422846Y172654D02*
Y168695D01*
G01X424446Y168864D02*
Y172746D01*
G01X424188Y125734D02*
X423882Y124296D01*
G01X425240Y130683D02*
X424934Y129245D01*
G01X426446Y136360D02*
X425986Y134194D01*
G01X424810Y136360D02*
X424421Y134527D01*
G01X419143Y170725D02*
X426446Y136360D01*
G01X417676Y169929D02*
X424810Y136360D01*
G01X418400Y171468D02*
X419143Y170725D01*
G01X416800Y170805D02*
X417676Y169929D01*
G01X418400Y172257D02*
Y171468D01*
G01X416800Y172192D02*
Y170805D01*
G01X424188Y125734D02*
X423882Y124296D01*
G01X425240Y130683D02*
X424934Y129245D01*
G01X424810Y136360D02*
X424421Y134527D01*
G01X426446Y136360D02*
X425986Y134194D01*
G01X417676Y169929D02*
X424810Y136360D01*
G01X419143Y170725D02*
X426446Y136360D01*
G01X416800Y170805D02*
X417676Y169929D01*
G01X418400Y171468D02*
X419143Y170725D01*
G01X416800Y172192D02*
Y170805D01*
G01X418400Y172257D02*
Y171468D01*
G01X412450Y171949D02*
Y172750D01*
G01X410850Y171286D02*
Y172650D01*
G01X413469Y170930D02*
X412450Y171949D01*
G01X412002Y170134D02*
X410850Y171286D01*
G01X420573Y137478D02*
X413469Y170930D01*
G01X418937Y137478D02*
X412002Y170134D01*
G01X419864Y134141D02*
X420573Y137478D01*
G01X418812Y129191D02*
X419117Y130629D01*
G01X417760Y124242D02*
X418065Y125680D01*
G01X410850Y171286D02*
Y172650D01*
G01X412450Y171949D02*
Y172750D01*
G01X412002Y170134D02*
X410850Y171286D01*
G01X413469Y170930D02*
X412450Y171949D01*
G01X418937Y137478D02*
X412002Y170134D01*
G01X420573Y137478D02*
X413469Y170930D01*
G01X419864Y134141D02*
X420573Y137478D01*
G01X418812Y129191D02*
X419117Y130629D01*
G01X417760Y124242D02*
X418065Y125680D01*
G01X411474Y123155D02*
X411168Y121717D01*
G01X412525Y128104D02*
X412220Y126666D01*
G01X414118Y135594D02*
X413272Y131616D01*
G01X415033Y139905D02*
X414117Y135594D01*
G01X408920Y168683D02*
X415033Y139905D01*
G01X407453Y167887D02*
X413397Y139905D01*
G01X406431Y171172D02*
X408920Y168683D01*
G01X404831Y170509D02*
X407453Y167887D01*
G01X406431Y172731D02*
Y171172D01*
G01X404831Y172669D02*
Y170509D01*
G01X411474Y123155D02*
X411168Y121717D01*
G01X412525Y128104D02*
X412220Y126666D01*
G01X414118Y135594D02*
X413272Y131616D01*
G01X415033Y139905D02*
X414117Y135594D01*
G01X407453Y167887D02*
X413397Y139905D01*
G01X408920Y168683D02*
X415033Y139905D01*
G01X404831Y170509D02*
X407453Y167887D01*
G01X406431Y171172D02*
X408920Y168683D01*
G01X404831Y172669D02*
Y170509D01*
G01X406431Y172731D02*
Y171172D01*
G01X406072Y126499D02*
X405766Y125061D01*
G01X407124Y131449D02*
X406818Y130011D01*
G01X408559Y138203D02*
X407870Y134961D01*
G01X409318Y141777D02*
X408559Y138203D01*
G01X404000Y166804D02*
X409318Y141777D01*
G01X402533Y166008D02*
X407682Y141777D01*
G01X400433Y170371D02*
X404000Y166804D01*
G01X398833Y169708D02*
X402533Y166008D01*
G01X400433Y172733D02*
Y170371D01*
G01X398833Y172667D02*
Y169708D01*
G01X406072Y126499D02*
X405766Y125061D01*
G01X407124Y131449D02*
X406818Y130011D01*
G01X408559Y138203D02*
X407870Y134961D01*
G01X409318Y141777D02*
X408559Y138203D01*
G01X402533Y166008D02*
X407682Y141777D01*
G01X404000Y166804D02*
X409318Y141777D01*
G01X398833Y169708D02*
X402533Y166008D01*
G01X400433Y170371D02*
X404000Y166804D01*
G01X398833Y172667D02*
Y169708D01*
G01X400433Y172733D02*
Y170371D01*
G01X401709Y149115D02*
X403458Y140881D01*
G01X397051Y163341D02*
X401822Y140881D01*
G01X400658Y154065D02*
X400963Y152627D01*
G01X397051Y163341D02*
X401822Y140881D01*
G01X399606Y159014D02*
X399912Y157577D01*
G01X397051Y163341D02*
X401822Y140881D01*
G01X398677Y163387D02*
X398860Y162526D01*
G01X397051Y163341D02*
X401822Y140881D01*
G01X398555Y163964D02*
X398677Y163387D01*
G01X397051Y163341D02*
X401822Y140881D01*
G01X394655Y169968D02*
X398555Y163964D01*
G01X393151Y169346D02*
X397051Y163341D01*
G01X394444Y170961D02*
X394655Y169968D01*
G01X392844Y170793D02*
X393151Y169346D01*
G01X394444Y172744D02*
Y170961D01*
G01X392844Y172656D02*
Y170793D01*
G01X397051Y163341D02*
X401822Y140881D01*
G01X401709Y149115D02*
X403458Y140881D01*
G01X400658Y154065D02*
X400963Y152627D01*
G01X399606Y159014D02*
X399912Y157577D01*
G01X398677Y163387D02*
X398860Y162526D01*
G01X398555Y163964D02*
X398677Y163387D01*
G01X393151Y169346D02*
X397051Y163341D01*
G01X394655Y169968D02*
X398555Y163964D01*
G01X392844Y170793D02*
X393151Y169346D01*
G01X394444Y170961D02*
X394655Y169968D01*
G01X392844Y172656D02*
Y170793D01*
G01X394444Y172744D02*
Y170961D01*
G01X392581Y163987D02*
X397564Y140554D01*
G01X391077Y163364D02*
X395928Y140554D01*
G01X388438Y170365D02*
X392581Y163987D01*
G01X388438Y172738D02*
Y170365D01*
G01X386838Y172662D02*
Y169890D01*
G01X391077Y163364D02*
X395928Y140554D01*
G01X392581Y163987D02*
X397564Y140554D01*
G01X388438Y170365D02*
X392581Y163987D01*
G01X386838Y172662D02*
Y169890D01*
G01X388438Y172738D02*
Y170365D01*
G01X387982Y162213D02*
X392358Y141623D01*
G01X387982Y162213D02*
X392358Y141623D01*
G01X448370Y177662D02*
Y176430D01*
G01X446770Y184661D02*
Y176270D01*
G01X448370Y183998D02*
Y181252D01*
G01X446770Y184661D02*
Y176270D01*
G01X453225Y188853D02*
X448370Y183998D01*
G01X451625Y189516D02*
X446770Y184661D01*
G01D02*
Y176270D01*
G01X448370Y177662D02*
Y176430D01*
G01Y183998D02*
Y181252D01*
G01X451625Y189516D02*
X446770Y184661D01*
G01X453225Y188853D02*
X448370Y183998D01*
G01X442307Y178462D02*
Y177085D01*
G01X440707Y185381D02*
Y176899D01*
G01X442307Y184718D02*
Y182052D01*
G01X440707Y185381D02*
Y176899D01*
G01X447658Y190069D02*
X442307Y184718D01*
G01X446058Y190732D02*
X440707Y185381D01*
G01X447658Y198654D02*
Y190069D01*
G01X446058Y198654D02*
Y190732D01*
G01X440707Y185381D02*
Y176899D01*
G01X442307Y178462D02*
Y177085D01*
G01Y184718D02*
Y182052D01*
G01X446058Y190732D02*
X440707Y185381D01*
G01X447658Y190069D02*
X442307Y184718D01*
G01X446058Y198654D02*
Y190732D01*
G01X447658Y198654D02*
Y190069D01*
G01X436307Y178462D02*
Y177085D01*
G01X434707Y186249D02*
Y176899D01*
G01X436307Y185586D02*
Y182052D01*
G01X434707Y186249D02*
Y176899D01*
G01X443313Y192592D02*
X436307Y185586D01*
G01X441713Y193255D02*
X434707Y186249D01*
G01X443313Y197031D02*
Y192592D01*
G01X441713Y197031D02*
Y193255D01*
G01X434707Y186249D02*
Y176899D01*
G01X436307Y178462D02*
Y177085D01*
G01Y185586D02*
Y182052D01*
G01X441713Y193255D02*
X434707Y186249D01*
G01X443313Y192592D02*
X436307Y185586D01*
G01X441713Y197031D02*
Y193255D01*
G01X443313Y197031D02*
Y192592D01*
G01X430338Y178647D02*
Y177054D01*
G01X428738Y187080D02*
Y176930D01*
G01X430338Y186417D02*
Y182237D01*
G01X428738Y187080D02*
Y176930D01*
G01X438663Y194742D02*
X430338Y186417D01*
G01X437063Y195405D02*
X428738Y187080D01*
G01X438663Y197031D02*
Y194742D01*
G01X437063Y197031D02*
Y195405D01*
G01X428738Y187080D02*
Y176930D01*
G01X430338Y178647D02*
Y177054D01*
G01Y186417D02*
Y182237D01*
G01X437063Y195405D02*
X428738Y187080D01*
G01X438663Y194742D02*
X430338Y186417D01*
G01X437063Y197031D02*
Y195405D01*
G01X438663Y197031D02*
Y194742D01*
G01X424261Y178692D02*
Y177131D01*
G01X422661Y188930D02*
Y176853D01*
G01X424261Y188267D02*
Y182282D01*
G01X422661Y188930D02*
Y176853D01*
G01X432055Y196061D02*
X424261Y188267D01*
G01X430455Y196724D02*
X422661Y188930D01*
G01X432055Y199262D02*
Y196061D01*
G01X430455Y199262D02*
Y196724D01*
G01X422661Y188930D02*
Y176853D01*
G01X424261Y178692D02*
Y177131D01*
G01Y188267D02*
Y182282D01*
G01X430455Y196724D02*
X422661Y188930D01*
G01X432055Y196061D02*
X424261Y188267D01*
G01X430455Y199262D02*
Y196724D01*
G01X432055Y199262D02*
Y196061D01*
G01X418284Y178853D02*
Y177131D01*
G01X416684Y176784D02*
Y188621D01*
G01X418284Y187958D02*
Y182443D01*
G01X416684Y176784D02*
Y188621D01*
G01X428111Y197785D02*
X418284Y187958D01*
G01X416684Y188621D02*
X426511Y198448D01*
G01X428111Y199344D02*
Y197785D01*
G01X426511Y198448D02*
Y199344D01*
G01Y198448D02*
Y199344D01*
G01X428111D02*
Y197785D01*
G01X416684Y188621D02*
X426511Y198448D01*
G01X428111Y197785D02*
X418284Y187958D01*
G01X416684Y176784D02*
Y188621D01*
G01X418284Y178853D02*
Y177131D01*
G01Y187958D02*
Y182443D01*
G01X424157Y198419D02*
Y199493D01*
G01X422557Y199082D02*
Y199567D01*
G01X412285Y186547D02*
X424157Y198419D01*
G01X410685Y187210D02*
X422557Y199082D01*
G01X412285Y184528D02*
Y186547D01*
G01X410685Y176377D02*
Y187210D01*
G01X412285Y176607D02*
Y180938D01*
G01X410685Y176377D02*
Y187210D01*
G01X422557Y199082D02*
Y199567D01*
G01X424157Y198419D02*
Y199493D01*
G01X410685Y187210D02*
X422557Y199082D01*
G01X412285Y186547D02*
X424157Y198419D01*
G01X410685Y176377D02*
Y187210D01*
G01X412285Y184528D02*
Y186547D01*
G01Y176607D02*
Y180938D01*
G01X416353Y195820D02*
Y198248D01*
G01X414753Y196483D02*
Y198248D01*
G01X406353Y185820D02*
X416353Y195820D01*
G01X404753Y186483D02*
X414753Y196483D01*
G01X406353Y184393D02*
Y185820D01*
G01X404753Y176353D02*
Y186483D01*
G01X406353Y176447D02*
Y180803D01*
G01X404753Y176353D02*
Y186483D01*
G01X414753Y196483D02*
Y198248D01*
G01X416353Y195820D02*
Y198248D01*
G01X404753Y186483D02*
X414753Y196483D01*
G01X406353Y185820D02*
X416353Y195820D01*
G01X404753Y176353D02*
Y186483D01*
G01X406353Y184393D02*
Y185820D01*
G01Y176447D02*
Y180803D01*
G01X412329Y197607D02*
Y198786D01*
G01X410729Y198270D02*
Y198786D01*
G01X400263Y185541D02*
X412329Y197607D01*
G01X398663Y186204D02*
X410729Y198270D01*
G01X400263Y184032D02*
Y185541D01*
G01X398663Y176537D02*
Y186204D01*
G01X400263Y176801D02*
Y180442D01*
G01X398663Y176537D02*
Y186204D01*
G01X410729Y198270D02*
Y198786D01*
G01X412329Y197607D02*
Y198786D01*
G01X398663Y186204D02*
X410729Y198270D01*
G01X400263Y185541D02*
X412329Y197607D01*
G01X398663Y176537D02*
Y186204D01*
G01X400263Y184032D02*
Y185541D01*
G01Y176801D02*
Y180442D01*
G01X399740Y189420D02*
X407124Y196804D01*
G01X399077Y191020D02*
X405992Y197935D01*
G01X395486Y189420D02*
X399740D01*
G01X394823Y191020D02*
X399077D01*
G01X394349Y188283D02*
X395486Y189420D01*
G01X392749Y188946D02*
X394823Y191020D01*
G01X394349Y186846D02*
Y188283D01*
G01X392749Y176349D02*
Y188946D01*
G01X394349Y181686D02*
Y183156D01*
G01X392749Y176349D02*
Y188946D01*
G01X394349Y176479D02*
Y177996D01*
G01X392749Y176349D02*
Y188946D01*
G01X399077Y191020D02*
X405992Y197935D01*
G01X399740Y189420D02*
X407124Y196804D01*
G01X394823Y191020D02*
X399077D01*
G01X395486Y189420D02*
X399740D01*
G01X392749Y188946D02*
X394823Y191020D01*
G01X394349Y188283D02*
X395486Y189420D01*
G01X392749Y176349D02*
Y188946D01*
G01X394349Y186846D02*
Y188283D01*
G01Y181686D02*
Y183156D01*
G01Y176479D02*
Y177996D01*
G01X399187Y193316D02*
X403355Y197484D01*
G01X398524Y194916D02*
X402190Y198582D01*
G01X392488Y193316D02*
X399187D01*
G01X391825Y194916D02*
X398524D01*
G01X388354Y189182D02*
X392488Y193316D01*
G01X388354Y187735D02*
Y189182D01*
G01Y182675D02*
Y184145D01*
G01Y177038D02*
Y179085D01*
G01X387817Y202043D02*
X388433D01*
G01X387154Y203643D02*
X388433D01*
G01X387154D02*
X388433D01*
G01X387817Y202043D02*
X388433D01*
G01X389238Y215368D02*
X387227D01*
G01X389238D02*
X387227D01*
G01X398524Y194916D02*
X402190Y198582D01*
G01X399187Y193316D02*
X403355Y197484D01*
G01X391825Y194916D02*
X398524D01*
G01X392488Y193316D02*
X399187D01*
G01X388354Y189182D02*
X392488Y193316D01*
G01X388354Y187735D02*
Y189182D01*
G01Y182675D02*
Y184145D01*
G01Y177038D02*
Y179085D01*
G01X389662Y197926D02*
X391424D01*
G01X388999Y199526D02*
X391424D01*
G01X388999D02*
X391424D01*
G01X389662Y197926D02*
X391424D01*
G01X404831Y452574D02*
X405558Y453692D01*
G01X403327Y453197D02*
X404310Y454708D01*
G01X404534Y451164D02*
X404831Y452574D01*
G01X402898Y451163D02*
X403327Y453197D01*
G01X404803Y449896D02*
X404534Y451164D01*
G01X403299Y449274D02*
X402898Y451163D01*
G01X405644Y448600D02*
X404803Y449896D01*
G01X404487Y447443D02*
X403299Y449274D01*
G01X407818Y447190D02*
X405644Y448600D01*
G01X407195Y445686D02*
X404487Y447443D01*
G01X409997Y446726D02*
X407818Y447190D01*
G01X409828Y445126D02*
X407195Y445686D01*
G01X424686Y446726D02*
X409997D01*
G01X424517Y445126D02*
X409828D01*
G01X478852Y435215D02*
X424686Y446726D01*
G01X478230Y433710D02*
X424517Y445126D01*
G01X403327Y453197D02*
X404310Y454708D01*
G01X404831Y452574D02*
X405558Y453692D01*
G01X402898Y451163D02*
X403327Y453197D01*
G01X404534Y451164D02*
X404831Y452574D01*
G01X403299Y449274D02*
X402898Y451163D01*
G01X404803Y449896D02*
X404534Y451164D01*
G01X404487Y447443D02*
X403299Y449274D01*
G01X405644Y448600D02*
X404803Y449896D01*
G01X407195Y445686D02*
X404487Y447443D01*
G01X407818Y447190D02*
X405644Y448600D01*
G01X409828Y445126D02*
X407195Y445686D01*
G01X409997Y446726D02*
X407818Y447190D01*
G01X424517Y445126D02*
X409828D01*
G01X424686Y446726D02*
X409997D01*
G01X478230Y433710D02*
X424517Y445126D01*
G01X478852Y435215D02*
X424686Y446726D01*
G01X413758Y452700D02*
X414361Y453634D01*
G01X412254Y453323D02*
X413114Y454654D01*
G01X413627Y452084D02*
X413758Y452700D01*
G01X411990Y452083D02*
X412254Y453323D01*
G01X413751Y451502D02*
X413627Y452084D01*
G01X412247Y450880D02*
X411990Y452083D01*
G01X414494Y450352D02*
X413751Y451502D01*
G01X413336Y449196D02*
X412247Y450880D01*
G01X415109Y449953D02*
X414494Y450352D01*
G01X414486Y448449D02*
X413336Y449196D01*
G01X416119Y449738D02*
X415109Y449953D01*
G01X415951Y448138D02*
X414486Y448449D01*
G01X434976Y449738D02*
X416119D01*
G01X434807Y448138D02*
X415951D01*
G01X480286Y440109D02*
X434976Y449738D01*
G01X479663Y438604D02*
X434807Y448138D01*
G01X412254Y453323D02*
X413114Y454654D01*
G01X413758Y452700D02*
X414361Y453634D01*
G01X411990Y452083D02*
X412254Y453323D01*
G01X413627Y452084D02*
X413758Y452700D01*
G01X412247Y450880D02*
X411990Y452083D01*
G01X413751Y451502D02*
X413627Y452084D01*
G01X413336Y449196D02*
X412247Y450880D01*
G01X414494Y450352D02*
X413751Y451502D01*
G01X414486Y448449D02*
X413336Y449196D01*
G01X415109Y449953D02*
X414494Y450352D01*
G01X415951Y448138D02*
X414486Y448449D01*
G01X416119Y449738D02*
X415109Y449953D01*
G01X434807Y448138D02*
X415951D01*
G01X434976Y449738D02*
X416119D01*
G01X479663Y438604D02*
X434807Y448138D01*
G01X480286Y440109D02*
X434976Y449738D01*
G01X404674Y437385D02*
X405538Y438713D01*
G01X403169Y438007D02*
X404288Y439726D01*
G01X404462Y436373D02*
X404674Y437385D01*
G01X402826Y436372D02*
X403169Y438007D01*
G01X404792Y434806D02*
X404462Y436373D01*
G01X403288Y434184D02*
X402826Y436372D01*
G01X405479Y433748D02*
X404792Y434806D01*
G01X404322Y432591D02*
X403288Y434184D01*
G01X407817Y432230D02*
X405479Y433748D01*
G01X407195Y430726D02*
X404322Y432591D01*
G01X409842Y431799D02*
X407817Y432230D01*
G01X409673Y430199D02*
X407195Y430726D01*
G01X442887Y431799D02*
X409842D01*
G01X442718Y430199D02*
X409673D01*
G01X477764Y424384D02*
X442887Y431799D01*
G01X477141Y422880D02*
X442718Y430199D01*
G01X403169Y438007D02*
X404288Y439726D01*
G01X404674Y437385D02*
X405538Y438713D01*
G01X402826Y436372D02*
X403169Y438007D01*
G01X404462Y436373D02*
X404674Y437385D01*
G01X403288Y434184D02*
X402826Y436372D01*
G01X404792Y434806D02*
X404462Y436373D01*
G01X404322Y432591D02*
X403288Y434184D01*
G01X405479Y433748D02*
X404792Y434806D01*
G01X407195Y430726D02*
X404322Y432591D01*
G01X407817Y432230D02*
X405479Y433748D01*
G01X409673Y430199D02*
X407195Y430726D01*
G01X409842Y431799D02*
X407817Y432230D01*
G01X442718Y430199D02*
X409673D01*
G01X442887Y431799D02*
X409842D01*
G01X477141Y422880D02*
X442718Y430199D01*
G01X477764Y424384D02*
X442887Y431799D01*
G01X413647Y437552D02*
X414394Y438708D01*
G01X412143Y438173D02*
X413148Y439728D01*
G01X413532Y437011D02*
X413647Y437552D01*
G01X411896Y437011D02*
X412143Y438173D01*
G01X413673Y436345D02*
X413532Y437011D01*
G01X412169Y435723D02*
X411896Y437011D01*
G01X414145Y435619D02*
X413673Y436345D01*
G01X412988Y434462D02*
X412169Y435723D01*
G01X415109Y434993D02*
X414145Y435619D01*
G01X414486Y433489D02*
X412988Y434462D01*
G01X416298Y434740D02*
X415109Y434993D01*
G01X416130Y433140D02*
X414486Y433489D01*
G01X427194Y434740D02*
X416298D01*
G01X427857Y433140D02*
X416130D01*
G01X429162Y436708D02*
X427194Y434740D01*
G01X429825Y435108D02*
X427857Y433140D01*
G01X446657Y436708D02*
X429162D01*
G01X446488Y435108D02*
X429825D01*
G01X477905Y430068D02*
X446657Y436708D01*
G01X477282Y428563D02*
X446488Y435108D01*
G01X412143Y438173D02*
X413148Y439728D01*
G01X413647Y437552D02*
X414394Y438708D01*
G01X411896Y437011D02*
X412143Y438173D01*
G01X413532Y437011D02*
X413647Y437552D01*
G01X412169Y435723D02*
X411896Y437011D01*
G01X413673Y436345D02*
X413532Y437011D01*
G01X412988Y434462D02*
X412169Y435723D01*
G01X414145Y435619D02*
X413673Y436345D01*
G01X414486Y433489D02*
X412988Y434462D01*
G01X415109Y434993D02*
X414145Y435619D01*
G01X416130Y433140D02*
X414486Y433489D01*
G01X416298Y434740D02*
X415109Y434993D01*
G01X427857Y433140D02*
X416130D01*
G01X427194Y434740D02*
X416298D01*
G01X429825Y435108D02*
X427857Y433140D01*
G01X429162Y436708D02*
X427194Y434740D01*
G01X446488Y435108D02*
X429825D01*
G01X446657Y436708D02*
X429162D01*
G01X477282Y428563D02*
X446488Y435108D01*
G01X477905Y430068D02*
X446657Y436708D01*
G01X499750Y13792D02*
X501106D01*
G01X499750Y12192D02*
X501106D01*
G01X498832Y14710D02*
G03X499750Y13792I918J0D01*
G01X497232Y14710D02*
G03X499750Y12192I2518J0D01*
G01X498832Y62671D02*
Y14710D01*
G01X497232Y62840D02*
Y14710D01*
G01X499750Y12192D02*
X501106D01*
G01X499750Y13792D02*
X501106D01*
G01X497232Y14710D02*
G03X499750Y12192I2518J0D01*
G01X498832Y14710D02*
G03X499750Y13792I918J0D01*
G01X497232Y62840D02*
Y14710D01*
G01X498832Y62671D02*
Y14710D01*
G01X491746Y19435D02*
Y58484D01*
G01X490146Y19435D02*
Y58653D01*
G01X492664Y18517D02*
G02X491746Y19435I0J918D01*
G01X492664Y16917D02*
G02X490146Y19435I0J2518D01*
G01X494020Y18517D02*
X492664D01*
G01X494020Y16917D02*
X492664D01*
G01X490146Y19435D02*
Y58653D01*
G01X491746Y19435D02*
Y58484D01*
G01X492664Y16917D02*
G02X490146Y19435I0J2518D01*
G01X492664Y18517D02*
G02X491746Y19435I0J918D01*
G01X494020Y16917D02*
X492664D01*
G01X494020Y18517D02*
X492664D01*
G01X484659Y14710D02*
Y57738D01*
G01X483059Y14710D02*
Y57907D01*
G01X485577Y13792D02*
G02X484659Y14710I0J918D01*
G01X485577Y12192D02*
G02X483059Y14710I0J2518D01*
G01X486933Y13792D02*
X485577D01*
G01X486933Y12192D02*
X485577D01*
G01X483059Y14710D02*
Y57907D01*
G01X484659Y14710D02*
Y57738D01*
G01X485577Y12192D02*
G02X483059Y14710I0J2518D01*
G01X485577Y13792D02*
G02X484659Y14710I0J918D01*
G01X486933Y12192D02*
X485577D01*
G01X486933Y13792D02*
X485577D01*
G01X477572Y19435D02*
Y65767D01*
G01X475972Y19435D02*
Y65936D01*
G01X478490Y18517D02*
G02X477572Y19435I0J918D01*
G01X478490Y16917D02*
G02X475972Y19435I0J2518D01*
G01X479846Y18517D02*
X478490D01*
G01X479846Y16917D02*
X478490D01*
G01X475972Y19435D02*
Y65936D01*
G01X477572Y19435D02*
Y65767D01*
G01X478490Y16917D02*
G02X475972Y19435I0J2518D01*
G01X478490Y18517D02*
G02X477572Y19435I0J918D01*
G01X479846Y16917D02*
X478490D01*
G01X479846Y18517D02*
X478490D01*
G01X470486Y14710D02*
Y48433D01*
G01X468886Y14710D02*
Y48434D01*
G01X471404Y13792D02*
G02X470486Y14710I0J918D01*
G01X471404Y12192D02*
G02X468886Y14710I0J2518D01*
G01X472760Y13792D02*
X471404D01*
G01X472760Y12192D02*
X471404D01*
G01X468886Y14710D02*
Y48434D01*
G01X470486Y14710D02*
Y48433D01*
G01X471404Y12192D02*
G02X468886Y14710I0J2518D01*
G01X471404Y13792D02*
G02X470486Y14710I0J918D01*
G01X472760Y12192D02*
X471404D01*
G01X472760Y13792D02*
X471404D01*
G01X464317Y18517D02*
X465673D01*
G01X464317Y16917D02*
X465673D01*
G01X463399Y19435D02*
G03X464317Y18517I918J0D01*
G01X461799Y19435D02*
G03X464317Y16917I2518J0D01*
G01X463399Y71395D02*
Y19435D01*
G01X461799Y71563D02*
Y19435D01*
G01X464317Y16917D02*
X465673D01*
G01X464317Y18517D02*
X465673D01*
G01X461799Y19435D02*
G03X464317Y16917I2518J0D01*
G01X463399Y19435D02*
G03X464317Y18517I918J0D01*
G01X461799Y71563D02*
Y19435D01*
G01X463399Y71395D02*
Y19435D01*
G01X457230Y13792D02*
X458586D01*
G01X457230Y12192D02*
X458586D01*
G01X456312Y14710D02*
G03X457230Y13792I918J0D01*
G01X454712Y14710D02*
G03X457230Y12192I2518J0D01*
G01X456312Y70344D02*
Y14710D01*
G01X454712Y70506D02*
Y14710D01*
G01X457230Y12192D02*
X458586D01*
G01X457230Y13792D02*
X458586D01*
G01X454712Y14710D02*
G03X457230Y12192I2518J0D01*
G01X456312Y14710D02*
G03X457230Y13792I918J0D01*
G01X454712Y70506D02*
Y14710D01*
G01X456312Y70344D02*
Y14710D01*
G01X450144Y18517D02*
X451500D01*
G01X450144Y16917D02*
X451500D01*
G01X449226Y19435D02*
G03X450144Y18517I918J0D01*
G01X449226Y69446D02*
Y19435D01*
G01X505919D02*
Y63281D01*
G01X504319Y19435D02*
Y63450D01*
G01X506837Y18517D02*
G02X505919Y19435I0J918D01*
G01X506837Y16917D02*
G02X504319Y19435I0J2518D01*
G01X508193Y18517D02*
X506837D01*
G01X508193Y16917D02*
X506837D01*
G01X504319Y19435D02*
Y63450D01*
G01X505919Y19435D02*
Y63281D01*
G01X506837Y16917D02*
G02X504319Y19435I0J2518D01*
G01X506837Y18517D02*
G02X505919Y19435I0J918D01*
G01X508193Y16917D02*
X506837D01*
G01X508193Y18517D02*
X506837D01*
G01X450144Y16917D02*
X451500D01*
G01X450144Y18517D02*
X451500D01*
G01X449226Y19435D02*
G03X450144Y18517I918J0D01*
G01X449226Y69446D02*
Y19435D01*
G01X504033Y87129D02*
X498832Y62671D01*
G01X505554Y101977D02*
X497232Y62840D01*
G01X505086Y92078D02*
X504780Y90640D01*
G01X505554Y101977D02*
X497232Y62840D01*
G01X506138Y97027D02*
X505832Y95589D01*
G01X505554Y101977D02*
X497232Y62840D01*
G01X507190Y101976D02*
X506884Y100538D01*
G01X505554Y101977D02*
X497232Y62840D01*
G01X501442Y129108D02*
X507190Y101976D01*
G01X499842Y128940D02*
X505554Y101977D01*
G01D02*
X497232Y62840D01*
G01X504033Y87129D02*
X498832Y62671D01*
G01X505086Y92078D02*
X504780Y90640D01*
G01X506138Y97027D02*
X505832Y95589D01*
G01X507190Y101976D02*
X506884Y100538D01*
G01X499842Y128940D02*
X505554Y101977D01*
G01X501442Y129108D02*
X507190Y101976D01*
G01X501168Y102785D02*
X494099Y136172D01*
G01X499532Y102786D02*
X492499Y136004D01*
G01X500862Y101347D02*
X501168Y102785D01*
G01X490146Y58653D02*
X499532Y102786D01*
G01X499810Y96398D02*
X500116Y97836D01*
G01X490146Y58653D02*
X499532Y102786D01*
G01X498758Y91449D02*
X499064Y92887D01*
G01X490146Y58653D02*
X499532Y102786D01*
G01X491746Y58484D02*
X498011Y87937D01*
G01X490146Y58653D02*
X499532Y102786D01*
G01D02*
X492499Y136004D01*
G01X501168Y102785D02*
X494099Y136172D01*
G01X490146Y58653D02*
X499532Y102786D01*
G01X500862Y101347D02*
X501168Y102785D01*
G01X499810Y96398D02*
X500116Y97836D01*
G01X498758Y91449D02*
X499064Y92887D01*
G01X491746Y58484D02*
X498011Y87937D01*
G01X494610Y104562D02*
X487070Y140178D01*
G01X492974Y104563D02*
X485470Y140010D01*
G01X494218Y102717D02*
X494610Y104562D01*
G01X483059Y57907D02*
X492974Y104563D01*
G01X493166Y97767D02*
X493472Y99205D01*
G01X483059Y57907D02*
X492974Y104563D01*
G01X492114Y92818D02*
X492420Y94256D01*
G01X483059Y57907D02*
X492974Y104563D01*
G01X484659Y57738D02*
X491368Y89306D01*
G01X483059Y57907D02*
X492974Y104563D01*
G01D02*
X485470Y140010D01*
G01X494610Y104562D02*
X487070Y140178D01*
G01X483059Y57907D02*
X492974Y104563D01*
G01X494218Y102717D02*
X494610Y104562D01*
G01X493166Y97767D02*
X493472Y99205D01*
G01X492114Y92818D02*
X492420Y94256D01*
G01X484659Y57738D02*
X491368Y89306D01*
G01X487186Y111000D02*
X480050Y144711D01*
G01X485550Y111001D02*
X478450Y144543D01*
G01X486613Y108305D02*
X487186Y111000D01*
G01X475972Y65936D02*
X485550Y111001D01*
G01X485561Y103355D02*
X485867Y104793D01*
G01X475972Y65936D02*
X485550Y111001D01*
G01X484509Y98406D02*
X484815Y99844D01*
G01X475972Y65936D02*
X485550Y111001D01*
G01X477572Y65767D02*
X483763Y94894D01*
G01X475972Y65936D02*
X485550Y111001D01*
G01D02*
X478450Y144543D01*
G01X487186Y111000D02*
X480050Y144711D01*
G01X475972Y65936D02*
X485550Y111001D01*
G01X486613Y108305D02*
X487186Y111000D01*
G01X485561Y103355D02*
X485867Y104793D01*
G01X484509Y98406D02*
X484815Y99844D01*
G01X477572Y65767D02*
X483763Y94894D01*
G01X480182Y112363D02*
X480494Y113833D01*
G01X468885Y66911D02*
X478858Y113834D01*
G01X479130Y107414D02*
X479435Y108852D01*
G01X468885Y66911D02*
X478858Y113834D01*
G01X478078Y102464D02*
X478383Y103902D01*
G01X468885Y66911D02*
X478858Y113834D01*
G01X470490Y66766D02*
X477331Y98953D01*
G01X468885Y66911D02*
X478858Y113834D01*
G01X468885Y66911D02*
X478858Y113834D01*
G01X480182Y112363D02*
X480494Y113833D01*
G01X479130Y107414D02*
X479435Y108852D01*
G01X478078Y102464D02*
X478383Y103902D01*
G01X470490Y66766D02*
X477331Y98953D01*
G01X470309Y103953D02*
X463399Y71395D01*
G01X471914Y119226D02*
X461799Y71563D01*
G01X471360Y108903D02*
X471055Y107465D01*
G01X471914Y119226D02*
X461799Y71563D01*
G01X472410Y113853D02*
X472105Y112415D01*
G01X471914Y119226D02*
X461799Y71563D01*
G01X471914Y119226D02*
X461799Y71563D01*
G01X471914Y119226D02*
X461799Y71563D01*
G01X470309Y103953D02*
X463399Y71395D01*
G01X471360Y108903D02*
X471055Y107465D01*
G01X472410Y113853D02*
X472105Y112415D01*
G01X463132Y103737D02*
X456312Y70344D01*
G01X465273Y122221D02*
X454712Y70506D01*
G01X464144Y108695D02*
X463850Y107255D01*
G01X465273Y122221D02*
X454712Y70506D01*
G01X465157Y113653D02*
X464863Y112213D01*
G01X465273Y122221D02*
X454712Y70506D01*
G01X465273Y122221D02*
X454712Y70506D01*
G01X465273Y122221D02*
X454712Y70506D01*
G01X463132Y103737D02*
X456312Y70344D01*
G01X464144Y108695D02*
X463850Y107255D01*
G01X465157Y113653D02*
X464863Y112213D01*
G01X456993Y106001D02*
X449226Y69446D01*
G01X458045Y110950D02*
X457739Y109512D01*
G01X513364Y98309D02*
X506556Y130452D01*
G01X511728Y98310D02*
X504920Y130453D01*
G01X504319Y63450D02*
X511728Y98310D01*
G01X504319Y63450D02*
X511728Y98310D01*
G01X510936Y86883D02*
X511241Y88321D01*
G01X504319Y63450D02*
X511728Y98310D01*
G01X505919Y63281D02*
X510189Y83372D01*
G01X504319Y63450D02*
X511728Y98310D01*
G01D02*
X504920Y130453D01*
G01X513364Y98309D02*
X506556Y130452D01*
G01X504319Y63450D02*
X511728Y98310D01*
G01X510936Y86883D02*
X511241Y88321D01*
G01X505919Y63281D02*
X510189Y83372D01*
G01X456993Y106001D02*
X449226Y69446D01*
G01X458045Y110950D02*
X457739Y109512D01*
G01X452619Y113629D02*
X452313Y112191D01*
G01X452619Y113629D02*
X452313Y112191D01*
G01X510197Y130331D02*
X517055Y162598D01*
G01X518390Y91775D02*
X510197Y130331D01*
G01X501301Y160336D02*
Y157799D01*
G01X499701Y160167D02*
Y157601D01*
G01X494843Y190722D02*
X501301Y160336D01*
G01X493339Y190099D02*
X499701Y160167D01*
G01D02*
Y157601D01*
G01X501301Y160336D02*
Y157799D01*
G01X493339Y190099D02*
X499701Y160167D01*
G01X494843Y190722D02*
X501301Y160336D01*
G01X494000Y162013D02*
Y157800D01*
G01X492400Y161539D02*
Y157800D01*
G01X490125Y167980D02*
X494000Y162013D01*
G01X488621Y167357D02*
X492400Y161539D01*
G01X487530Y180188D02*
X490125Y167980D01*
G01X485930Y180018D02*
X488621Y167357D01*
G01X492400Y161539D02*
Y157800D01*
G01X494000Y162013D02*
Y157800D01*
G01X488621Y167357D02*
X492400Y161539D01*
G01X490125Y167980D02*
X494000Y162013D01*
G01X485930Y180018D02*
X488621Y167357D01*
G01X487530Y180188D02*
X490125Y167980D01*
G01X487100Y158664D02*
Y157600D01*
G01X485500Y158495D02*
Y157700D01*
G01X482691Y179408D02*
X487100Y158664D01*
G01X484404Y163650D02*
X485500Y158495D01*
G01X481091Y179239D02*
X484404Y163650D01*
G01X485500Y158495D02*
Y157700D01*
G01X487100Y158664D02*
Y157600D01*
G01X484404Y163650D02*
X485500Y158495D01*
G01X482691Y179408D02*
X487100Y158664D01*
G01X481091Y179239D02*
X484404Y163650D01*
G01X482691Y179408D02*
X487100Y158664D01*
G01X480000Y159258D02*
Y157900D01*
G01X478400Y164389D02*
Y157700D01*
G01X480000Y164542D02*
Y162960D01*
G01X478400Y164389D02*
Y157700D01*
G01X477875Y175582D02*
X480000Y164542D01*
G01X476275Y175429D02*
X478400Y164389D01*
G01D02*
Y157700D01*
G01X480000Y159258D02*
Y157900D01*
G01Y164542D02*
Y162960D01*
G01X476275Y175429D02*
X478400Y164389D01*
G01X477875Y175582D02*
X480000Y164542D01*
G01X506851Y171194D02*
X504696Y181336D01*
G01X505251Y171025D02*
X503060Y181336D01*
G01X506851Y163585D02*
Y171194D01*
G01X505251Y163604D02*
Y171025D01*
G01D02*
X503060Y181336D01*
G01X506851Y171194D02*
X504696Y181336D01*
G01X505251Y163604D02*
Y171025D01*
G01X506851Y163585D02*
Y171194D01*
G01X510197Y130331D02*
X517055Y162598D01*
G01X518390Y91775D02*
X510197Y130331D01*
G01X501442Y153942D02*
Y129108D01*
G01X499842Y153958D02*
Y128940D01*
G01Y153958D02*
Y128940D01*
G01X501442Y153942D02*
Y129108D01*
G01X494099Y136172D02*
Y153999D01*
G01X492499Y136004D02*
Y153901D01*
G01Y136004D02*
Y153901D01*
G01X494099Y136172D02*
Y153999D01*
G01X487070Y140178D02*
Y153970D01*
G01X485470Y140010D02*
Y153930D01*
G01Y140010D02*
Y153930D01*
G01X487070Y140178D02*
Y153970D01*
G01X480050Y144711D02*
Y153950D01*
G01X478450Y144543D02*
Y153950D01*
G01Y144543D02*
Y153950D01*
G01X480050Y144711D02*
Y153950D01*
G01X472400Y152054D02*
Y172700D01*
G01X470800Y151886D02*
Y172700D01*
G01X480494Y113833D02*
X472400Y152054D01*
G01X478858Y113834D02*
X470800Y151886D01*
G01D02*
Y172700D01*
G01X472400Y152054D02*
Y172700D01*
G01X478858Y113834D02*
X470800Y151886D01*
G01X480494Y113833D02*
X472400Y152054D01*
G01X473550Y119227D02*
X473155Y117365D01*
G01X466456Y152598D02*
X473550Y119227D01*
G01X464856Y152429D02*
X471914Y119226D01*
G01X466456Y172756D02*
Y152598D01*
G01X464856Y172644D02*
Y152429D01*
G01X473550Y119227D02*
X473155Y117365D01*
G01X464856Y152429D02*
X471914Y119226D01*
G01X466456Y152598D02*
X473550Y119227D01*
G01X464856Y172644D02*
Y152429D01*
G01X466456Y172756D02*
Y152598D01*
G01X466905Y122213D02*
X465875Y117171D01*
G01X460342Y156000D02*
X466905Y122213D01*
G01X458742Y155846D02*
X465273Y122221D01*
G01X460342Y172642D02*
Y156000D01*
G01X458742Y172758D02*
Y155846D01*
G01X466905Y122213D02*
X465875Y117171D01*
G01X458742Y155846D02*
X465273Y122221D01*
G01X460342Y156000D02*
X466905Y122213D01*
G01X458742Y172758D02*
Y155846D01*
G01X460342Y172642D02*
Y156000D01*
G01X459096Y115900D02*
X458791Y114462D01*
G01X461002Y124870D02*
X459842Y119411D01*
G01X454369Y156076D02*
X461002Y124870D01*
G01X452769Y155907D02*
X459366Y124870D01*
G01X454369Y172669D02*
Y156076D01*
G01X452769Y172731D02*
Y155907D01*
G01X506778Y157180D02*
Y159478D01*
G01X505178Y157011D02*
Y159422D01*
G01X509508Y144339D02*
X506778Y157180D01*
G01X507872Y144339D02*
X505178Y157011D01*
G01X506556Y130452D02*
X509508Y144339D01*
G01X504920Y130453D02*
X507872Y144339D01*
G01X505178Y157011D02*
Y159422D01*
G01X506778Y157180D02*
Y159478D01*
G01X507872Y144339D02*
X505178Y157011D01*
G01X509508Y144339D02*
X506778Y157180D01*
G01X504920Y130453D02*
X507872Y144339D01*
G01X506556Y130452D02*
X509508Y144339D01*
G01X459096Y115900D02*
X458791Y114462D01*
G01X461002Y124870D02*
X459842Y119411D01*
G01X452769Y155907D02*
X459366Y124870D01*
G01X454369Y156076D02*
X461002Y124870D01*
G01X452769Y172731D02*
Y155907D01*
G01X454369Y172669D02*
Y156076D01*
G01X453671Y118578D02*
X453365Y117140D01*
G01X454938Y124541D02*
X454417Y122090D01*
G01X453302Y124541D02*
X452852Y122423D01*
G01X453671Y118578D02*
X453365Y117140D01*
G01X453302Y124541D02*
X452852Y122423D01*
G01X454938Y124541D02*
X454417Y122090D01*
G01X491418Y195999D02*
X494843Y190722D01*
G01X490168Y194985D02*
X493339Y190099D01*
G01X489270Y198145D02*
X491418Y195999D01*
G01X488139Y197013D02*
X490168Y194985D01*
G01D02*
X493339Y190099D01*
G01X491418Y195999D02*
X494843Y190722D01*
G01X488139Y197013D02*
X490168Y194985D01*
G01X489270Y198145D02*
X491418Y195999D01*
G01X487530Y187689D02*
Y180188D01*
G01X485930Y192596D02*
Y180018D01*
G01X487530Y193259D02*
Y191789D01*
G01X485930Y192596D02*
Y180018D01*
G01X483083Y197706D02*
X487530Y193259D01*
G01X481483Y197043D02*
X485930Y192596D01*
G01X483083Y198291D02*
Y197706D01*
G01X481483Y198291D02*
Y197043D01*
G01X485930Y192596D02*
Y180018D01*
G01X487530Y187689D02*
Y180188D01*
G01Y193259D02*
Y191789D01*
G01X481483Y197043D02*
X485930Y192596D01*
G01X483083Y197706D02*
X487530Y193259D01*
G01X481483Y198291D02*
Y197043D01*
G01X483083Y198291D02*
Y197706D01*
G01X482691Y187886D02*
Y179408D01*
G01X481091Y192889D02*
Y179239D01*
G01X482691Y193552D02*
Y192082D01*
G01X481091Y192889D02*
Y179239D01*
G01X479149Y197094D02*
X482691Y193552D01*
G01X477549Y196431D02*
X481091Y192889D01*
G01X479149Y198291D02*
Y197094D01*
G01X477549Y198291D02*
Y196431D01*
G01X481091Y192889D02*
Y179239D01*
G01X482691Y187886D02*
Y179408D01*
G01Y193552D02*
Y192082D01*
G01X477549Y196431D02*
X481091Y192889D01*
G01X479149Y197094D02*
X482691Y193552D01*
G01X477549Y198291D02*
Y196431D01*
G01X479149Y198291D02*
Y197094D01*
G01X477875Y193495D02*
Y175582D01*
G01X476275Y192832D02*
Y175429D01*
G01X475215Y196155D02*
X477875Y193495D01*
G01X473615Y195492D02*
X476275Y192832D01*
G01X475215Y198291D02*
Y196155D01*
G01X473615Y198291D02*
Y195492D01*
G01X476275Y192832D02*
Y175429D01*
G01X477875Y193495D02*
Y175582D01*
G01X473615Y195492D02*
X476275Y192832D01*
G01X475215Y196155D02*
X477875Y193495D01*
G01X473615Y198291D02*
Y195492D01*
G01X475215Y198291D02*
Y196155D01*
G01X472400Y187584D02*
Y177100D01*
G01X470800Y177148D02*
Y192845D01*
G01X472400Y193508D02*
Y191732D01*
G01X470800Y177148D02*
Y192845D01*
G01X471266Y194642D02*
X472400Y193508D01*
G01X470800Y192845D02*
X469666Y193979D01*
G01X471266Y198741D02*
Y194642D01*
G01X469666Y193979D02*
Y198741D01*
G01Y193979D02*
Y198741D01*
G01X471266D02*
Y194642D01*
G01X470800Y192845D02*
X469666Y193979D01*
G01X471266Y194642D02*
X472400Y193508D01*
G01X470800Y177148D02*
Y192845D01*
G01X472400Y187584D02*
Y177100D01*
G01Y193508D02*
Y191732D01*
G01X466400Y180480D02*
Y176492D01*
G01X464800Y181143D02*
Y176492D01*
G01X467334Y181414D02*
X466400Y180480D01*
G01X465734Y182077D02*
X464800Y181143D01*
G01X467334Y188736D02*
Y181414D01*
G01X465734Y198291D02*
Y182077D01*
G01X467334Y198291D02*
Y192816D01*
G01X465734Y198291D02*
Y182077D01*
G01X464800Y181143D02*
Y176492D01*
G01X466400Y180480D02*
Y176492D01*
G01X465734Y182077D02*
X464800Y181143D01*
G01X467334Y181414D02*
X466400Y180480D01*
G01X465734Y198291D02*
Y182077D01*
G01X467334Y188736D02*
Y181414D01*
G01Y198291D02*
Y192816D01*
G01X460378Y182435D02*
Y177014D01*
G01X458778Y183098D02*
Y176970D01*
G01X462500Y184557D02*
X460378Y182435D01*
G01X460900Y185220D02*
X458778Y183098D01*
G01X462500Y190202D02*
Y184557D01*
G01X460900Y196309D02*
Y185220D01*
G01X462500Y195646D02*
Y194176D01*
G01X460900Y196309D02*
Y185220D01*
G01X463444Y196590D02*
X462500Y195646D01*
G01X461844Y197253D02*
X460900Y196309D01*
G01X463444Y198275D02*
Y196590D01*
G01X461844Y198275D02*
Y197253D01*
G01X458778Y183098D02*
Y176970D01*
G01X460378Y182435D02*
Y177014D01*
G01X460900Y185220D02*
X458778Y183098D01*
G01X462500Y184557D02*
X460378Y182435D01*
G01X460900Y196309D02*
Y185220D01*
G01X462500Y190202D02*
Y184557D01*
G01Y195646D02*
Y194176D01*
G01X461844Y197253D02*
X460900Y196309D01*
G01X463444Y196590D02*
X462500Y195646D01*
G01X461844Y198275D02*
Y197253D01*
G01X463444Y198275D02*
Y196590D01*
G01X454400Y177699D02*
Y176400D01*
G01X452800Y183910D02*
Y176300D01*
G01X454400Y183247D02*
Y181289D01*
G01X452800Y183910D02*
Y176300D01*
G01X457622Y186469D02*
X454400Y183247D01*
G01X456022Y187132D02*
X452800Y183910D01*
G01X457622Y195565D02*
Y186469D01*
G01X456022Y196228D02*
Y187132D01*
G01X459553Y197496D02*
X457622Y195565D01*
G01X457953Y198159D02*
X456022Y196228D01*
G01X459553Y198809D02*
Y197496D01*
G01X457953Y198809D02*
Y198159D01*
G01X452800Y183910D02*
Y176300D01*
G01X454400Y177699D02*
Y176400D01*
G01Y183247D02*
Y181289D01*
G01X456022Y187132D02*
X452800Y183910D01*
G01X457622Y186469D02*
X454400Y183247D01*
G01X456022Y196228D02*
Y187132D01*
G01X457622Y195565D02*
Y186469D01*
G01X457953Y198159D02*
X456022Y196228D01*
G01X459553Y197496D02*
X457622Y195565D01*
G01X457953Y198809D02*
Y198159D01*
G01X459553Y198809D02*
Y197496D01*
G01X508783Y192916D02*
X514174Y196417D01*
G01X507625Y194073D02*
X513017Y197574D01*
G01X506365Y189190D02*
X508783Y192916D01*
G01X504861Y189813D02*
X507625Y194073D01*
G01X504696Y181336D02*
X506365Y189190D01*
G01X503060Y181336D02*
X504861Y189813D01*
G01X507625Y194073D02*
X513017Y197574D01*
G01X508783Y192916D02*
X514174Y196417D01*
G01X504861Y189813D02*
X507625Y194073D01*
G01X506365Y189190D02*
X508783Y192916D01*
G01X503060Y181336D02*
X504861Y189813D01*
G01X504696Y181336D02*
X506365Y189190D01*
G01X453225Y200185D02*
Y188853D01*
G01X451625Y200185D02*
Y189516D01*
G01Y200185D02*
Y189516D01*
G01X453225Y200185D02*
Y188853D01*
G01X511229Y296245D02*
X509757D01*
G01X511892Y297845D02*
X509757D01*
G01X511892D02*
X509757D01*
G01X511229Y296245D02*
X509757D01*
G01X512010Y291137D02*
X510540D01*
G01X522115Y292737D02*
X510540D01*
G01X522115D02*
X510540D01*
G01X522115D02*
X510540D01*
G01X512010Y291137D02*
X510540D01*
G01X516833Y303723D02*
X510414D01*
G01X516170Y305323D02*
X510414D01*
G01X516170D02*
X510414D01*
G01X516833Y303723D02*
X510414D01*
G01X509490Y300192D02*
X517604D01*
G01X509490Y301792D02*
X516941D01*
G01X509490D02*
X516941D01*
G01X509490Y300192D02*
X517604D01*
G01X560175Y382404D02*
X478852Y435215D01*
G01X559018Y381247D02*
X478230Y433710D01*
G01X559018Y381247D02*
X478230Y433710D01*
G01X560175Y382404D02*
X478852Y435215D01*
G01X563659Y385964D02*
X480286Y440109D01*
G01X562502Y384807D02*
X479663Y438604D01*
G01X562502Y384807D02*
X479663Y438604D01*
G01X563659Y385964D02*
X480286Y440109D01*
G01X552801Y375653D02*
X477764Y424384D01*
G01X551644Y374496D02*
X477141Y422880D01*
G01X551644Y374496D02*
X477141Y422880D01*
G01X552801Y375653D02*
X477764Y424384D01*
G01X556450Y379055D02*
X477905Y430068D01*
G01X555293Y377898D02*
X477282Y428563D01*
G01X555293Y377898D02*
X477282Y428563D01*
G01X556450Y379055D02*
X477905Y430068D01*
G01X570616Y13792D02*
X571972D01*
G01X570616Y12192D02*
X571972D01*
G01X569698Y14710D02*
G03X570616Y13792I918J0D01*
G01X568098Y14710D02*
G03X570616Y12192I2518J0D01*
G01X569698Y59750D02*
Y14710D01*
G01X568098Y59581D02*
Y14710D01*
G01X570616Y12192D02*
X571972D01*
G01X570616Y13792D02*
X571972D01*
G01X568098Y14710D02*
G03X570616Y12192I2518J0D01*
G01X569698Y14710D02*
G03X570616Y13792I918J0D01*
G01X568098Y59581D02*
Y14710D01*
G01X569698Y59750D02*
Y14710D01*
G01X563530Y18517D02*
X564886D01*
G01X563530Y16917D02*
X564886D01*
G01X562612Y19435D02*
G03X563530Y18517I918J0D01*
G01X561012Y19435D02*
G03X563530Y16917I2518J0D01*
G01X562612Y68559D02*
Y19435D01*
G01X561012Y68390D02*
Y19435D01*
G01X563530Y16917D02*
X564886D01*
G01X563530Y18517D02*
X564886D01*
G01X561012Y19435D02*
G03X563530Y16917I2518J0D01*
G01X562612Y19435D02*
G03X563530Y18517I918J0D01*
G01X561012Y68390D02*
Y19435D01*
G01X562612Y68559D02*
Y19435D01*
G01X528097Y13792D02*
X529453D01*
G01X528097Y12192D02*
X529453D01*
G01X527179Y14710D02*
G03X528097Y13792I918J0D01*
G01X525579Y14710D02*
G03X528097Y12192I2518J0D01*
G01X527179Y63607D02*
Y14710D01*
G01X525579Y63776D02*
Y14710D01*
G01X528097Y12192D02*
X529453D01*
G01X528097Y13792D02*
X529453D01*
G01X525579Y14710D02*
G03X528097Y12192I2518J0D01*
G01X527179Y14710D02*
G03X528097Y13792I918J0D01*
G01X525579Y63776D02*
Y14710D01*
G01X527179Y63607D02*
Y14710D01*
G01X520092Y19435D02*
Y63696D01*
G01X518492Y19435D02*
Y63865D01*
G01X521010Y18517D02*
G02X520092Y19435I0J918D01*
G01X521010Y16917D02*
G02X518492Y19435I0J2518D01*
G01X522366Y18517D02*
X521010D01*
G01X522366Y16917D02*
X521010D01*
G01X518492Y19435D02*
Y63865D01*
G01X520092Y19435D02*
Y63696D01*
G01X521010Y16917D02*
G02X518492Y19435I0J2518D01*
G01X521010Y18517D02*
G02X520092Y19435I0J918D01*
G01X522366Y16917D02*
X521010D01*
G01X522366Y18517D02*
X521010D01*
G01X556443Y13792D02*
X557799D01*
G01X556443Y12192D02*
X557799D01*
G01X555525Y14710D02*
G03X556443Y13792I918J0D01*
G01X553925Y14710D02*
G03X556443Y12192I2518J0D01*
G01X555525Y59973D02*
Y14710D01*
G01X553925Y60112D02*
Y14710D01*
G01X556443Y12192D02*
X557799D01*
G01X556443Y13792D02*
X557799D01*
G01X553925Y14710D02*
G03X556443Y12192I2518J0D01*
G01X555525Y14710D02*
G03X556443Y13792I918J0D01*
G01X553925Y60112D02*
Y14710D01*
G01X555525Y59973D02*
Y14710D01*
G01X513005D02*
Y58728D01*
G01X511405Y14710D02*
Y58896D01*
G01X513923Y13792D02*
G02X513005Y14710I0J918D01*
G01X513923Y12192D02*
G02X511405Y14710I0J2518D01*
G01X515279Y13792D02*
X513923D01*
G01X515279Y12192D02*
X513923D01*
G01X549356Y18517D02*
X550712D01*
G01X549356Y16917D02*
X550712D01*
G01X548438Y19435D02*
G03X549356Y18517I918J0D01*
G01X546838Y19435D02*
G03X549356Y16917I2518J0D01*
G01X548438Y62108D02*
Y19435D01*
G01X546838Y62276D02*
Y19435D01*
G01X549356Y16917D02*
X550712D01*
G01X549356Y18517D02*
X550712D01*
G01X546838Y19435D02*
G03X549356Y16917I2518J0D01*
G01X548438Y19435D02*
G03X549356Y18517I918J0D01*
G01X546838Y62276D02*
Y19435D01*
G01X548438Y62108D02*
Y19435D01*
G01X542270Y13792D02*
X543626D01*
G01X542270Y12192D02*
X543626D01*
G01X541352Y14710D02*
G03X542270Y13792I918J0D01*
G01X539752Y14710D02*
G03X542270Y12192I2518J0D01*
G01X541352Y63700D02*
Y14710D01*
G01X539752Y63869D02*
Y14710D01*
G01X542270Y12192D02*
X543626D01*
G01X542270Y13792D02*
X543626D01*
G01X539752Y14710D02*
G03X542270Y12192I2518J0D01*
G01X541352Y14710D02*
G03X542270Y13792I918J0D01*
G01X539752Y63869D02*
Y14710D01*
G01X541352Y63700D02*
Y14710D01*
G01X535183Y18517D02*
X536539D01*
G01X535183Y16917D02*
X536539D01*
G01X534265Y19435D02*
G03X535183Y18517I918J0D01*
G01X532665Y19435D02*
G03X535183Y16917I2518J0D01*
G01X534265Y67636D02*
Y19435D01*
G01X532665Y67805D02*
Y19435D01*
G01X535183Y16917D02*
X536539D01*
G01X535183Y18517D02*
X536539D01*
G01X532665Y19435D02*
G03X535183Y16917I2518J0D01*
G01X534265Y19435D02*
G03X535183Y18517I918J0D01*
G01X532665Y67805D02*
Y19435D01*
G01X534265Y67636D02*
Y19435D01*
G01X511405Y14710D02*
Y58896D01*
G01X513005Y14710D02*
Y58728D01*
G01X513923Y12192D02*
G02X511405Y14710I0J2518D01*
G01X513923Y13792D02*
G02X513005Y14710I0J918D01*
G01X515279Y12192D02*
X513923D01*
G01X515279Y13792D02*
X513923D01*
G01X565560Y126708D02*
X578915Y63888D01*
G01X563924Y126708D02*
X577411Y63265D01*
G01X563924Y126708D02*
X577411Y63265D01*
G01X565560Y126708D02*
X578915Y63888D01*
G01X560289Y128433D02*
X576785Y50819D01*
G01X558653Y128433D02*
X575185Y50650D01*
G01X558653Y128433D02*
X575185Y50650D01*
G01X560289Y128433D02*
X576785Y50819D01*
G01X555057Y128636D02*
X569698Y59750D01*
G01X553421Y128636D02*
X568098Y59581D01*
G01X553421Y128636D02*
X568098Y59581D01*
G01X555057Y128636D02*
X569698Y59750D01*
G01X549841Y128645D02*
X562612Y68559D01*
G01X548205Y128645D02*
X561012Y68390D01*
G01X548205Y128645D02*
X561012Y68390D01*
G01X549841Y128645D02*
X562612Y68559D01*
G01X532115Y86829D02*
X527179Y63607D01*
G01X530479Y86829D02*
X525579Y63776D01*
G01X526349Y113957D02*
X532115Y86829D01*
G01X524783Y113623D02*
X530479Y86829D01*
G01D02*
X525579Y63776D01*
G01X532115Y86829D02*
X527179Y63607D01*
G01X524783Y113623D02*
X530479Y86829D01*
G01X526349Y113957D02*
X532115Y86829D01*
G01X523863Y89130D02*
X515687Y127589D01*
G01X523863Y89130D02*
X515687Y127589D01*
G01X520382Y113202D02*
X520076Y114640D01*
G01X523863Y89130D02*
X515687Y127589D01*
G01X525499Y89130D02*
X521128Y109691D01*
G01X523863Y89130D02*
X515687Y127589D01*
G01X520092Y63696D02*
X525499Y89130D01*
G01X518492Y63865D02*
X523863Y89130D01*
G01D02*
X515687Y127589D01*
G01X520382Y113202D02*
X520076Y114640D01*
G01X525499Y89130D02*
X521128Y109691D01*
G01X518492Y63865D02*
X523863Y89130D01*
G01X520092Y63696D02*
X525499Y89130D01*
G01X557372Y69209D02*
X555525Y59973D01*
G01X555738Y69199D02*
X553921Y60116D01*
G01X544616Y129221D02*
X557372Y69209D01*
G01X542980Y129221D02*
X555738Y69199D01*
G01D02*
X553921Y60116D01*
G01X557372Y69209D02*
X555525Y59973D01*
G01X542980Y129221D02*
X555738Y69199D01*
G01X544616Y129221D02*
X557372Y69209D01*
G01X520026Y91775D02*
X511833Y130331D01*
G01X519721Y90337D02*
X520026Y91775D01*
G01X514967Y75665D02*
X518390Y91775D01*
G01X518669Y85388D02*
X518974Y86825D01*
G01X514967Y75665D02*
X518390Y91775D01*
G01X517617Y80438D02*
X517923Y81876D01*
G01X514967Y75665D02*
X518390Y91775D01*
G01X514115Y63953D02*
X516871Y76926D01*
G01X513372Y68160D02*
X514967Y75665D01*
G01X513971Y63275D02*
X514115Y63953D01*
G01X511405Y58896D02*
X513372Y68160D01*
G01X513730Y62138D02*
X513972Y63275D01*
G01X511405Y58896D02*
X513372Y68160D01*
G01X513005Y58728D02*
X513730Y62138D01*
G01X511405Y58896D02*
X513372Y68160D01*
G01X551130Y74795D02*
X548438Y62108D01*
G01X549494Y74795D02*
X546838Y62276D01*
G01X539468Y129671D02*
X551130Y74795D01*
G01X537832Y129671D02*
X549494Y74795D01*
G01D02*
X546838Y62276D01*
G01X551130Y74795D02*
X548438Y62108D01*
G01X537832Y129671D02*
X549494Y74795D01*
G01X539468Y129671D02*
X551130Y74795D01*
G01X544868Y80241D02*
X541352Y63700D01*
G01X543232Y80241D02*
X539752Y63869D01*
G01X534006Y131339D02*
X544868Y80241D01*
G01X532370Y131339D02*
X543232Y80241D01*
G01D02*
X539752Y63869D01*
G01X544868Y80241D02*
X541352Y63700D01*
G01X532370Y131339D02*
X543232Y80241D01*
G01X534006Y131339D02*
X544868Y80241D01*
G01X538374Y86974D02*
X534265Y67636D01*
G01X536738Y86974D02*
X532665Y67805D01*
G01X528861Y131727D02*
X538374Y86974D01*
G01X527225Y131727D02*
X536738Y86974D01*
G01D02*
X532665Y67805D01*
G01X538374Y86974D02*
X534265Y67636D01*
G01X527225Y131727D02*
X536738Y86974D01*
G01X528861Y131727D02*
X538374Y86974D01*
G01X520026Y91775D02*
X511833Y130331D01*
G01X514967Y75665D02*
X518390Y91775D01*
G01X519721Y90337D02*
X520026Y91775D01*
G01X518669Y85388D02*
X518974Y86825D01*
G01X517617Y80438D02*
X517923Y81876D01*
G01X513372Y68160D02*
X514967Y75665D01*
G01X514115Y63953D02*
X516871Y76926D01*
G01X511405Y58896D02*
X513372Y68160D01*
G01X513971Y63275D02*
X514115Y63953D01*
G01X513730Y62138D02*
X513972Y63275D01*
G01X513005Y58728D02*
X513730Y62138D01*
G01X513039Y96782D02*
X513364Y98309D01*
G01X511988Y91833D02*
X512293Y93271D01*
G01X513039Y96782D02*
X513364Y98309D01*
G01X511988Y91833D02*
X512293Y93271D01*
G01X576085Y176220D02*
X565560Y126708D01*
G01X574449Y176220D02*
X563924Y126708D01*
G01X574449Y176220D02*
X563924Y126708D01*
G01X576085Y176220D02*
X565560Y126708D01*
G01X570796Y177865D02*
X560289Y128433D01*
G01X569160Y177865D02*
X558653Y128433D01*
G01X569160Y177865D02*
X558653Y128433D01*
G01X570796Y177865D02*
X560289Y128433D01*
G01X565668Y178559D02*
X555057Y128636D01*
G01X564032Y178559D02*
X553421Y128636D01*
G01X564032Y178559D02*
X553421Y128636D01*
G01X565668Y178559D02*
X555057Y128636D01*
G01X560468Y178651D02*
X549841Y128645D01*
G01X558903Y178984D02*
X548205Y128645D01*
G01X558903Y178984D02*
X548205Y128645D01*
G01X558903Y178984D02*
X548205Y128645D01*
G01X560468Y178651D02*
X549841Y128645D01*
G01X525297Y118906D02*
X525603Y117468D01*
G01X521557Y128804D02*
X524784Y113623D01*
G01X524245Y123855D02*
X524551Y122417D01*
G01X521557Y128804D02*
X524784Y113623D01*
G01X523193Y128804D02*
X523499Y127366D01*
G01X521557Y128804D02*
X524784Y113623D01*
G01X534803Y183418D02*
X523193Y128804D01*
G01X533167Y183418D02*
X521557Y128804D01*
G01D02*
X524784Y113623D01*
G01X525297Y118906D02*
X525603Y117468D01*
G01X524245Y123855D02*
X524551Y122417D01*
G01X523193Y128804D02*
X523499Y127366D01*
G01X533167Y183418D02*
X521557Y128804D01*
G01X534803Y183418D02*
X523193Y128804D01*
G01X526650Y171470D02*
Y173450D01*
G01X525050Y171639D02*
Y173350D01*
G01X517323Y127589D02*
X526650Y171470D01*
G01X515687Y127589D02*
X525050Y171639D01*
G01X518277Y123101D02*
X517323Y127589D01*
G01X519329Y118152D02*
X519024Y119589D01*
G01X525050Y171639D02*
Y173350D01*
G01X526650Y171470D02*
Y173450D01*
G01X515687Y127589D02*
X525050Y171639D01*
G01X517323Y127589D02*
X526650Y171470D01*
G01X518277Y123101D02*
X517323Y127589D01*
G01X519329Y118152D02*
X519024Y119589D01*
G01X555363Y179782D02*
X544616Y129221D01*
G01X553727Y179782D02*
X542980Y129221D01*
G01X553727Y179782D02*
X542980Y129221D01*
G01X555363Y179782D02*
X544616Y129221D01*
G01X516900Y171025D02*
Y173267D01*
G01X515300Y170856D02*
Y173377D01*
G01X518691Y162598D02*
X516900Y171025D01*
G01X517055Y162598D02*
X515300Y170856D01*
G01X511833Y130331D02*
X518691Y162598D01*
G01X550247Y180385D02*
X539468Y129671D01*
G01X548611Y180385D02*
X537832Y129671D01*
G01X548611Y180385D02*
X537832Y129671D01*
G01X550247Y180385D02*
X539468Y129671D01*
G01X544860Y182409D02*
X534006Y131339D01*
G01X543224Y182409D02*
X532370Y131339D01*
G01X543224Y182409D02*
X532370Y131339D01*
G01X544860Y182409D02*
X534006Y131339D01*
G01X539794Y183159D02*
X528861Y131727D01*
G01X538158Y183159D02*
X527225Y131727D01*
G01X538158Y183159D02*
X527225Y131727D01*
G01X539794Y183159D02*
X528861Y131727D01*
G01X515300Y170856D02*
Y173377D01*
G01X516900Y171025D02*
Y173267D01*
G01X517055Y162598D02*
X515300Y170856D01*
G01X518691Y162598D02*
X516900Y171025D01*
G01X511833Y130331D02*
X518691Y162598D01*
G01X569283Y184981D02*
X570796Y177865D01*
G01X567647Y184981D02*
X569160Y177865D01*
G01X575588Y214678D02*
X569283Y184981D01*
G01X574084Y215301D02*
X567647Y184981D01*
G01D02*
X569160Y177865D01*
G01X569283Y184981D02*
X570796Y177865D01*
G01X574084Y215301D02*
X567647Y184981D01*
G01X575588Y214678D02*
X569283Y184981D01*
G01X563774Y187468D02*
X565668Y178559D01*
G01X562138Y187468D02*
X564032Y178559D01*
G01X569523Y214520D02*
X563774Y187468D01*
G01X568019Y215143D02*
X562138Y187468D01*
G01X575155Y223192D02*
X569523Y214520D01*
G01X573651Y223815D02*
X568019Y215143D01*
G01X562138Y187468D02*
X564032Y178559D01*
G01X563774Y187468D02*
X565668Y178559D01*
G01X568019Y215143D02*
X562138Y187468D01*
G01X569523Y214520D02*
X563774Y187468D01*
G01X573651Y223815D02*
X568019Y215143D01*
G01X575155Y223192D02*
X569523Y214520D01*
G01X560539Y178984D02*
X560469Y178651D01*
G01X558257Y189718D02*
X560539Y178984D01*
G01X556621Y189718D02*
X558903Y178984D01*
G01X563513Y214446D02*
X558257Y189718D01*
G01X562009Y215069D02*
X556621Y189718D01*
G01X570293Y224886D02*
X563513Y214446D01*
G01X568789Y225509D02*
X562009Y215069D01*
G01X574052Y242574D02*
X570293Y224886D01*
G01X572416Y242574D02*
X568789Y225509D01*
G01X560539Y178984D02*
X560469Y178651D01*
G01X556621Y189718D02*
X558903Y178984D01*
G01X558257Y189718D02*
X560539Y178984D01*
G01X562009Y215069D02*
X556621Y189718D01*
G01X563513Y214446D02*
X558257Y189718D01*
G01X568789Y225509D02*
X562009Y215069D01*
G01X570293Y224886D02*
X563513Y214446D01*
G01X572416Y242574D02*
X568789Y225509D01*
G01X574052Y242574D02*
X570293Y224886D01*
G01X531752Y197767D02*
X534803Y183418D01*
G01X530116Y197767D02*
X533167Y183418D01*
G01X534198Y209268D02*
X531752Y197767D01*
G01X532598Y209437D02*
X530116Y197767D01*
G01X534198Y212330D02*
Y209268D01*
G01X532598Y212161D02*
Y209437D01*
G01X533093Y217527D02*
X534198Y212330D01*
G01X531493Y217358D02*
X532598Y212161D01*
G01X533093Y220867D02*
Y217527D01*
G01X531493Y220267D02*
Y217358D01*
G01X530116Y197767D02*
X533167Y183418D01*
G01X531752Y197767D02*
X534803Y183418D01*
G01X532598Y209437D02*
X530116Y197767D01*
G01X534198Y209268D02*
X531752Y197767D01*
G01X532598Y212161D02*
Y209437D01*
G01X534198Y212330D02*
Y209268D01*
G01X531493Y217358D02*
X532598Y212161D01*
G01X533093Y217527D02*
X534198Y212330D01*
G01X531493Y220267D02*
Y217358D01*
G01X533093Y220867D02*
Y217527D01*
G01X552753Y192058D02*
X555363Y179782D01*
G01X551117Y192058D02*
X553727Y179782D01*
G01X557494Y214358D02*
X552753Y192058D01*
G01X555990Y214981D02*
X551117Y192058D01*
G01X565252Y226303D02*
X557494Y214358D01*
G01X563748Y226926D02*
X555990Y214981D01*
G01X568911Y243521D02*
X565252Y226303D01*
G01X567275Y243521D02*
X563748Y226926D01*
G01X551117Y192058D02*
X553727Y179782D01*
G01X552753Y192058D02*
X555363Y179782D01*
G01X555990Y214981D02*
X551117Y192058D01*
G01X557494Y214358D02*
X552753Y192058D01*
G01X563748Y226926D02*
X555990Y214981D01*
G01X565252Y226303D02*
X557494Y214358D01*
G01X567275Y243521D02*
X563748Y226926D01*
G01X568911Y243521D02*
X565252Y226303D01*
G01X547193Y194751D02*
X550247Y180385D01*
G01X545557Y194751D02*
X548611Y180385D01*
G01X551276Y213967D02*
X547193Y194751D01*
G01X549772Y214590D02*
X545557Y194751D01*
G01X560355Y227944D02*
X551276Y213967D01*
G01X558851Y228567D02*
X549772Y214590D01*
G01X563741Y243870D02*
X560355Y227944D01*
G01X562105Y243870D02*
X558851Y228567D01*
G01X545557Y194751D02*
X548611Y180385D01*
G01X547193Y194751D02*
X550247Y180385D01*
G01X549772Y214590D02*
X545557Y194751D01*
G01X551276Y213967D02*
X547193Y194751D01*
G01X558851Y228567D02*
X549772Y214590D01*
G01X560355Y227944D02*
X551276Y213967D01*
G01X562105Y243870D02*
X558851Y228567D01*
G01X563741Y243870D02*
X560355Y227944D01*
G01X543481Y188893D02*
X544860Y182409D01*
G01X540608Y194711D02*
X543224Y182409D01*
G01X542863Y191802D02*
X543481Y188893D01*
G01X540608Y194711D02*
X543224Y182409D01*
G01X542244Y194711D02*
X542863Y191802D01*
G01X540608Y194711D02*
X543224Y182409D01*
G01X546225Y213434D02*
X542244Y194711D01*
G01X544589Y213434D02*
X540608Y194711D01*
G01X538444Y250055D02*
X546225Y213434D01*
G01X536940Y249432D02*
X544589Y213434D01*
G01X540608Y194711D02*
X543224Y182409D01*
G01X543481Y188893D02*
X544860Y182409D01*
G01X542863Y191802D02*
X543481Y188893D01*
G01X542244Y194711D02*
X542863Y191802D01*
G01X544589Y213434D02*
X540608Y194711D01*
G01X546225Y213434D02*
X542244Y194711D01*
G01X536940Y249432D02*
X544589Y213434D01*
G01X538444Y250055D02*
X546225Y213434D01*
G01X536692Y197757D02*
X539794Y183159D01*
G01X535056Y197757D02*
X538158Y183159D01*
G01X536954Y198988D02*
X536692Y197757D01*
G01X539031Y216481D02*
X535056Y197757D01*
G01X538005Y203938D02*
X537700Y202500D01*
G01X539031Y216481D02*
X535056Y197757D01*
G01X539056Y208888D02*
X538751Y207450D01*
G01X539031Y216481D02*
X535056Y197757D01*
G01X540667Y216481D02*
X539802Y212400D01*
G01X539031Y216481D02*
X535056Y197757D01*
G01X537466Y231524D02*
X540667Y216481D01*
G01X535999Y230727D02*
X539031Y216481D01*
G01X534053Y234937D02*
X537466Y231524D01*
G01X532453Y234273D02*
X535999Y230727D01*
G01X534053Y240190D02*
Y234937D01*
G01X532453Y239724D02*
Y234273D01*
G01X535056Y197757D02*
X538158Y183159D01*
G01X536692Y197757D02*
X539794Y183159D01*
G01X539031Y216481D02*
X535056Y197757D01*
G01X536954Y198988D02*
X536692Y197757D01*
G01X538005Y203938D02*
X537700Y202500D01*
G01X539056Y208888D02*
X538751Y207450D01*
G01X540667Y216481D02*
X539802Y212400D01*
G01X535999Y230727D02*
X539031Y216481D01*
G01X537466Y231524D02*
X540667Y216481D01*
G01X532453Y234273D02*
X535999Y230727D01*
G01X534053Y234937D02*
X537466Y231524D01*
G01X532453Y239724D02*
Y234273D01*
G01X534053Y240190D02*
Y234937D01*
G01X528287Y233020D02*
Y242011D01*
G01X526687Y232357D02*
Y236288D01*
G01X533093Y228214D02*
X528287Y233020D01*
G01X531493Y227551D02*
X526687Y232357D01*
G01X533093Y223067D02*
Y228214D01*
G01X531493Y224073D02*
Y227551D01*
G01X528287Y233020D02*
Y242011D01*
G01X526687Y232357D02*
Y236288D01*
G01X528287Y233020D02*
Y242011D01*
G01X531493Y227551D02*
X526687Y232357D01*
G01X533093Y228214D02*
X528287Y233020D01*
G01X531493Y224073D02*
Y227551D01*
G01X533093Y223067D02*
Y228214D01*
G01X526532Y179100D02*
Y177950D01*
G01X524932Y179269D02*
Y177682D01*
G01X528614Y188890D02*
X526532Y179100D01*
G01X526978Y188890D02*
X524932Y179269D01*
G01X526588Y198420D02*
X528614Y188890D01*
G01X526762Y189902D02*
X526978Y188890D01*
G01X524952Y198420D02*
X526016Y193413D01*
G01X529374Y211526D02*
X526588Y198420D01*
G01X527738Y211526D02*
X524952Y198420D01*
G01X526015Y227327D02*
X529374Y211526D01*
G01X524511Y226703D02*
X527738Y211526D01*
G01X523663Y230942D02*
X526015Y227327D01*
G01X522063Y230467D02*
X524511Y226703D01*
G01X523663Y241874D02*
Y230942D01*
G01X522063Y241211D02*
Y230467D01*
G01X524932Y179269D02*
Y177682D01*
G01X526532Y179100D02*
Y177950D01*
G01X526978Y188890D02*
X524932Y179269D01*
G01X528614Y188890D02*
X526532Y179100D01*
G01X526762Y189902D02*
X526978Y188890D01*
G01X526588Y198420D02*
X528614Y188890D01*
G01X524952Y198420D02*
X526016Y193413D01*
G01X526588Y198420D02*
X528614Y188890D01*
G01X527738Y211526D02*
X524952Y198420D01*
G01X529374Y211526D02*
X526588Y198420D01*
G01X524511Y226703D02*
X527738Y211526D01*
G01X526015Y227327D02*
X529374Y211526D01*
G01X522063Y230467D02*
X524511Y226703D01*
G01X523663Y230942D02*
X526015Y227327D01*
G01X522063Y241211D02*
Y230467D01*
G01X523663Y241874D02*
Y230942D01*
G01X516868Y178992D02*
Y177251D01*
G01X515268Y176968D02*
Y178823D01*
G01X515960Y183268D02*
X516868Y178992D01*
G01X515268Y178823D02*
X514290Y183429D01*
G01X522213Y197999D02*
X515960Y183268D01*
G01X519696Y196166D02*
X520679Y198483D01*
G01X514290Y183429D02*
X518293Y192862D01*
G01X525352Y212765D02*
X522213Y197999D01*
G01X520679Y198483D02*
X523716Y212765D01*
G01X522813Y224702D02*
X525352Y212765D01*
G01X523716D02*
X521309Y224079D01*
G01X520180Y228757D02*
X522813Y224702D01*
G01X521309Y224079D02*
X518580Y228283D01*
G01X520180Y240129D02*
Y228757D01*
G01X518580Y228283D02*
Y239466D01*
G01Y228283D02*
Y239466D01*
G01X520180Y240129D02*
Y228757D01*
G01X521309Y224079D02*
X518580Y228283D01*
G01X520180Y228757D02*
X522813Y224702D01*
G01X523716Y212765D02*
X521309Y224079D01*
G01X522813Y224702D02*
X525352Y212765D01*
G01X520679Y198483D02*
X523716Y212765D01*
G01X525352D02*
X522213Y197999D01*
G01X519696Y196166D02*
X520679Y198483D01*
G01X522213Y197999D02*
X515960Y183268D01*
G01X514290Y183429D02*
X518293Y192862D01*
G01X522213Y197999D02*
X515960Y183268D01*
G01X515268Y178823D02*
X514290Y183429D01*
G01X515960Y183268D02*
X516868Y178992D01*
G01X515268Y176968D02*
Y178823D01*
G01X516868Y178992D02*
Y177251D01*
G01X515300Y225463D02*
Y233300D01*
G01X513700Y224800D02*
Y233300D01*
G01X518549Y222215D02*
X515300Y225463D01*
G01X517291Y221209D02*
X513700Y224800D01*
G01X520157Y219670D02*
X518549Y222215D01*
G01X518651Y219057D02*
X517291Y221209D01*
G01X521551Y213106D02*
X520157Y219670D01*
G01X519915Y213106D02*
X518651Y219057D01*
G01X520352Y207467D02*
X521551Y213106D01*
G01X518627Y207052D02*
X519915Y213106D01*
G01X519866Y205180D02*
X520352Y207466D01*
G01X518362Y205803D02*
X518627Y207052D01*
G01X514174Y196417D02*
X519866Y205180D01*
G01X513017Y197574D02*
X518362Y205803D01*
G01X513700Y224800D02*
Y233300D01*
G01X515300Y225463D02*
Y233300D01*
G01X517291Y221209D02*
X513700Y224800D01*
G01X518549Y222215D02*
X515300Y225463D01*
G01X518651Y219057D02*
X517291Y221209D01*
G01X520157Y219670D02*
X518549Y222215D01*
G01X519915Y213106D02*
X518651Y219057D01*
G01X521551Y213106D02*
X520157Y219670D01*
G01X518627Y207052D02*
X519915Y213106D01*
G01X520352Y207467D02*
X521551Y213106D01*
G01X518362Y205803D02*
X518627Y207052D01*
G01X519866Y205180D02*
X520352Y207466D01*
G01X513017Y197574D02*
X518362Y205803D01*
G01X514174Y196417D02*
X519866Y205180D01*
G01X556660Y291065D02*
X575071Y279106D01*
G01X556037Y289561D02*
X573913Y277949D01*
G01X545949Y293341D02*
X556660Y291065D01*
G01X545780Y291741D02*
X556037Y289561D01*
G01X543951Y293341D02*
X545949D01*
G01X543833Y291741D02*
X545780D01*
G01X556037Y289561D02*
X573913Y277949D01*
G01X556660Y291065D02*
X575071Y279106D01*
G01X545780Y291741D02*
X556037Y289561D01*
G01X545949Y293341D02*
X556660Y291065D01*
G01X543833Y291741D02*
X545780D01*
G01X543951Y293341D02*
X545949D01*
G01X571316Y275742D02*
X580108Y262205D01*
G01X570159Y274585D02*
X574381Y268084D01*
G01X556026Y285673D02*
X571316Y275742D01*
G01X555403Y284169D02*
X570159Y274585D01*
G01X549575Y287044D02*
X556026Y285673D01*
G01X549406Y285444D02*
X555403Y284169D01*
G01X544148Y287044D02*
X549575D01*
G01X544036Y285444D02*
X549406D01*
G01X571316Y275742D02*
X580108Y262205D01*
G01X570159Y274585D02*
X574381Y268084D01*
G01X571316Y275742D02*
X580108Y262205D01*
G01X555403Y284169D02*
X570159Y274585D01*
G01X556026Y285673D02*
X571316Y275742D01*
G01X549406Y285444D02*
X555403Y284169D01*
G01X549575Y287044D02*
X556026Y285673D01*
G01X544036Y285444D02*
X549406D01*
G01X544148Y287044D02*
X549575D01*
G01X567229Y272593D02*
X575464Y259908D01*
G01X570016Y265361D02*
X573960Y259285D01*
G01X566072Y271436D02*
X570016Y265361D01*
G01X557789Y278724D02*
X567229Y272593D01*
G01X557166Y277220D02*
X566072Y271436D01*
G01X547543Y280900D02*
X557789Y278724D01*
G01X547374Y279300D02*
X557166Y277220D01*
G01X544192Y280900D02*
X547543D01*
G01X543992Y279300D02*
X547374D01*
G01X570016Y265361D02*
X573960Y259285D01*
G01X567229Y272593D02*
X575464Y259908D01*
G01X566072Y271436D02*
X570016Y265361D01*
G01X567229Y272593D02*
X575464Y259908D01*
G01X557166Y277220D02*
X566072Y271436D01*
G01X557789Y278724D02*
X567229Y272593D01*
G01X547374Y279300D02*
X557166Y277220D01*
G01X547543Y280900D02*
X557789Y278724D01*
G01X543992Y279300D02*
X547374D01*
G01X544192Y280900D02*
X547543D01*
G01X570740Y258172D02*
X574052Y242574D01*
G01X569236Y257549D02*
X572416Y242574D01*
G01X564882Y267185D02*
X570740Y258172D01*
G01X566480Y261790D02*
X569236Y257549D01*
G01X563725Y266028D02*
X566480Y261790D01*
G01X555707Y273148D02*
X564882Y267185D01*
G01X555084Y271644D02*
X563725Y266028D01*
G01X547663Y274859D02*
X555707Y273148D01*
G01X547494Y273259D02*
X555084Y271644D01*
G01X544133Y274859D02*
X547663D01*
G01X544051Y273259D02*
X547494D01*
G01X569236Y257549D02*
X572416Y242574D01*
G01X570740Y258172D02*
X574052Y242574D01*
G01X566480Y261790D02*
X569236Y257549D01*
G01X564882Y267185D02*
X570740Y258172D01*
G01X563725Y266028D02*
X566480Y261790D01*
G01X564882Y267185D02*
X570740Y258172D01*
G01X555084Y271644D02*
X563725Y266028D01*
G01X555707Y273148D02*
X564882Y267185D01*
G01X547494Y273259D02*
X555084Y271644D01*
G01X547663Y274859D02*
X555707Y273148D01*
G01X544051Y273259D02*
X547494D01*
G01X544133Y274859D02*
X547663D01*
G01X566277Y255904D02*
X568911Y243521D01*
G01X564773Y255281D02*
X567275Y243521D01*
G01X561974Y262527D02*
X566277Y255904D01*
G01X562794Y258326D02*
X564773Y255281D01*
G01X560817Y261370D02*
X562794Y258326D01*
G01X554474Y267398D02*
X561974Y262527D01*
G01X553851Y265894D02*
X560817Y261370D01*
G01X548392Y268690D02*
X554474Y267398D01*
G01X548223Y267090D02*
X553851Y265894D01*
G01X544202Y268690D02*
X548392D01*
G01X543982Y267090D02*
X548223D01*
G01X564773Y255281D02*
X567275Y243521D01*
G01X566277Y255904D02*
X568911Y243521D01*
G01X562794Y258326D02*
X564773Y255281D01*
G01X561974Y262527D02*
X566277Y255904D01*
G01X560817Y261370D02*
X562794Y258326D01*
G01X561974Y262527D02*
X566277Y255904D01*
G01X553851Y265894D02*
X560817Y261370D01*
G01X554474Y267398D02*
X561974Y262527D01*
G01X548223Y267090D02*
X553851Y265894D01*
G01X548392Y268690D02*
X554474Y267398D01*
G01X543982Y267090D02*
X548223D01*
G01X544202Y268690D02*
X548392D01*
G01X561582Y254035D02*
X563741Y243870D01*
G01X560078Y253412D02*
X562105Y243870D01*
G01X558456Y258852D02*
X561582Y254035D01*
G01X558250Y256229D02*
X560078Y253412D01*
G01X557298Y257695D02*
X558250Y256229D01*
G01X554559Y261383D02*
X558456Y258852D01*
G01X553924Y259887D02*
X557298Y257695D01*
G01X548843Y262702D02*
X554559Y261383D01*
G01X548660Y261102D02*
X553924Y259887D01*
G01X544190Y262702D02*
X548843D01*
G01X543994Y261102D02*
X548660D01*
G01X560078Y253412D02*
X562105Y243870D01*
G01X561582Y254035D02*
X563741Y243870D01*
G01X558250Y256229D02*
X560078Y253412D01*
G01X558456Y258852D02*
X561582Y254035D01*
G01X557298Y257695D02*
X558250Y256229D01*
G01X558456Y258852D02*
X561582Y254035D01*
G01X553924Y259887D02*
X557298Y257695D01*
G01X554559Y261383D02*
X558456Y258852D01*
G01X548660Y261102D02*
X553924Y259887D01*
G01X548843Y262702D02*
X554559Y261383D01*
G01X543994Y261102D02*
X548660D01*
G01X544190Y262702D02*
X548843D01*
G01X535982Y253845D02*
X538444Y250055D01*
G01X534731Y252832D02*
X536940Y249432D01*
G01X533944Y255884D02*
X535982Y253845D01*
G01X533280Y254284D02*
X534731Y252832D01*
G01X531816Y255884D02*
X533944D01*
G01X531784Y254284D02*
X533280D01*
G01X534731Y252832D02*
X536940Y249432D01*
G01X535982Y253845D02*
X538444Y250055D01*
G01X533280Y254284D02*
X534731Y252832D01*
G01X533944Y255884D02*
X535982Y253845D01*
G01X531784Y254284D02*
X533280D01*
G01X531816Y255884D02*
X533944D01*
G01X513482Y293992D02*
X511229Y296245D01*
G01X514145Y295592D02*
X511892Y297845D01*
G01X518828Y293992D02*
X513482D01*
G01X518165Y295592D02*
X514145D01*
G01X520564Y295728D02*
X518828Y293992D01*
G01X529686Y307113D02*
X518165Y295592D01*
G01X530349Y305513D02*
X523160Y298324D01*
G01X529686Y307113D02*
X518165Y295592D01*
G01X514145D02*
X511892Y297845D01*
G01X513482Y293992D02*
X511229Y296245D01*
G01X518165Y295592D02*
X514145D01*
G01X518828Y293992D02*
X513482D01*
G01X529686Y307113D02*
X518165Y295592D01*
G01X520564Y295728D02*
X518828Y293992D01*
G01X530349Y305513D02*
X523160Y298324D01*
G01X522778Y291137D02*
X515680D01*
G01X529648Y298007D02*
X522778Y291137D01*
G01X528985Y299607D02*
X522115Y292737D01*
G01X533101Y298007D02*
X529648D01*
G01X522778Y291137D02*
X515680D01*
G01X528985Y299607D02*
X522115Y292737D01*
G01X529648Y298007D02*
X522778Y291137D01*
G01X533101Y298007D02*
X529648D01*
G01X521016Y286279D02*
X516975D01*
G01X521679Y284679D02*
X516975D01*
G01X524017Y289280D02*
X521016Y286279D01*
G01X524680Y287680D02*
X521679Y284679D01*
G01X525906Y289280D02*
X524017D01*
G01X531600Y287680D02*
X524680D01*
G01X530937Y289280D02*
X529576D01*
G01X531600Y287680D02*
X524680D01*
G01X535631Y291711D02*
X531600Y287680D01*
G01X534968Y293311D02*
X530937Y289280D01*
G01X535631Y291711D02*
X531600Y287680D01*
G01X538019Y293311D02*
X534968D01*
G01X538197Y291711D02*
X535631D01*
G01X521679Y284679D02*
X516975D01*
G01X521016Y286279D02*
X516975D01*
G01X524680Y287680D02*
X521679Y284679D01*
G01X524017Y289280D02*
X521016Y286279D01*
G01X531600Y287680D02*
X524680D01*
G01X525906Y289280D02*
X524017D01*
G01X530937D02*
X529576D01*
G01X535631Y291711D02*
X531600Y287680D01*
G01X530937Y289280D02*
X529576D01*
G01X534968Y293311D02*
X530937Y289280D01*
G01X538197Y291711D02*
X535631D01*
G01X538019Y293311D02*
X534968D01*
G01X522080Y282428D02*
X516965D01*
G01X522743Y280828D02*
X516965D01*
G01X522871Y283219D02*
X522080Y282428D01*
G01X523534Y281619D02*
X522743Y280828D01*
G01X525330Y283219D02*
X522871D01*
G01X532324Y281619D02*
X523534D01*
G01X531661Y283219D02*
X529000D01*
G01X532324Y281619D02*
X523534D01*
G01X535449Y287007D02*
X531661Y283219D01*
G01X536112Y285407D02*
X532324Y281619D01*
G01X538215Y287007D02*
X535449D01*
G01X538401Y285407D02*
X536112D01*
G01X522743Y280828D02*
X516965D01*
G01X522080Y282428D02*
X516965D01*
G01X523534Y281619D02*
X522743Y280828D01*
G01X522871Y283219D02*
X522080Y282428D01*
G01X532324Y281619D02*
X523534D01*
G01X525330Y283219D02*
X522871D01*
G01X531661D02*
X529000D01*
G01X536112Y285407D02*
X532324Y281619D01*
G01X535449Y287007D02*
X531661Y283219D01*
G01X538401Y285407D02*
X536112D01*
G01X538215Y287007D02*
X535449D01*
G01X520207Y278364D02*
X518737D01*
G01X534299Y276764D02*
X518737D01*
G01X533636Y278364D02*
X523877D01*
G01X534299Y276764D02*
X518737D01*
G01X536188Y280916D02*
X533636Y278364D01*
G01X536851Y279316D02*
X534299Y276764D01*
G01X538392Y279316D02*
X536851D01*
G01X538399Y280916D02*
X536188D01*
G01X538392Y279316D02*
X536851D01*
G01X534299Y276764D02*
X518737D01*
G01X520207Y278364D02*
X518737D01*
G01X533636D02*
X523877D01*
G01X536851Y279316D02*
X534299Y276764D01*
G01X536188Y280916D02*
X533636Y278364D01*
G01X538392Y279316D02*
X536851D01*
G01X536188Y280916D02*
X533636Y278364D01*
G01X538399Y280916D02*
X536188D01*
G01X518839Y274464D02*
X517430D01*
G01X518176Y272864D02*
X517430D01*
G01X519782Y273521D02*
X518839Y274464D01*
G01X519119Y271921D02*
X518176Y272864D01*
G01X520772Y273521D02*
X519782D01*
G01X536262Y271921D02*
X519119D01*
G01X535599Y273521D02*
X524442D01*
G01X536262Y271921D02*
X519119D01*
G01X536865Y274787D02*
X535599Y273521D01*
G01X537528Y273187D02*
X536262Y271921D01*
G01X538195Y274787D02*
X536865D01*
G01X538421Y273187D02*
X537528D01*
G01X518176Y272864D02*
X517430D01*
G01X518839Y274464D02*
X517430D01*
G01X519119Y271921D02*
X518176Y272864D01*
G01X519782Y273521D02*
X518839Y274464D01*
G01X536262Y271921D02*
X519119D01*
G01X520772Y273521D02*
X519782D01*
G01X535599D02*
X524442D01*
G01X537528Y273187D02*
X536262Y271921D01*
G01X536865Y274787D02*
X535599Y273521D01*
G01X538421Y273187D02*
X537528D01*
G01X538195Y274787D02*
X536865D01*
G01X519766Y250532D02*
X517978D01*
G01X519103Y248932D02*
X517978D01*
G01X528287Y242011D02*
X519766Y250532D01*
G01X526687Y241348D02*
X519103Y248932D01*
G01X526687Y239878D02*
Y241348D01*
G01X519103Y248932D02*
X517978D01*
G01X519766Y250532D02*
X517978D01*
G01X526687Y241348D02*
X519103Y248932D01*
G01X528287Y242011D02*
X519766Y250532D01*
G01X526687Y239878D02*
Y241348D01*
G01X519655Y245882D02*
X523663Y241874D01*
G01X518523Y244751D02*
X522063Y241211D01*
G01X518523Y244751D02*
X522063Y241211D01*
G01X519655Y245882D02*
X523663Y241874D01*
G01X518425Y270483D02*
X517093D01*
G01X517762Y268883D02*
X517093D01*
G01X521240Y267668D02*
X518425Y270483D01*
G01X520577Y266068D02*
X517762Y268883D01*
G01X522710Y267668D02*
X521240D01*
G01X520577Y266068D02*
X517762Y268883D01*
G01X536684Y266068D02*
X520577D01*
G01X536021Y267668D02*
X526380D01*
G01X536684Y266068D02*
X520577D01*
G01X536999Y268646D02*
X536021Y267668D01*
G01X537662Y267046D02*
X536684Y266068D01*
G01X538600Y268646D02*
X536999D01*
G01X538462Y267046D02*
X537662D01*
G01X517762Y268883D02*
X517093D01*
G01X518425Y270483D02*
X517093D01*
G01X520577Y266068D02*
X517762Y268883D01*
G01X521240Y267668D02*
X518425Y270483D01*
G01X522710Y267668D02*
X521240D01*
G01X536684Y266068D02*
X520577D01*
G01X522710Y267668D02*
X521240D01*
G01X536021D02*
X526380D01*
G01X537662Y267046D02*
X536684Y266068D01*
G01X536999Y268646D02*
X536021Y267668D01*
G01X538462Y267046D02*
X537662D01*
G01X538600Y268646D02*
X536999D01*
G01X518754Y241555D02*
X520180Y240129D01*
G01X518580Y239466D02*
X517622Y240424D01*
G01X518580Y239466D02*
X517622Y240424D01*
G01X518754Y241555D02*
X520180Y240129D01*
G01X514631Y266623D02*
X513272D01*
G01X513968Y265023D02*
X513272D01*
G01X518454Y262800D02*
X514631Y266623D01*
G01X517791Y261200D02*
X513968Y265023D01*
G01X520015Y262800D02*
X518454D01*
G01X538408Y261200D02*
X517791D01*
G01X538408Y262800D02*
X523685D01*
G01X538408Y261200D02*
X517791D01*
G01X513968Y265023D02*
X513272D01*
G01X514631Y266623D02*
X513272D01*
G01X517791Y261200D02*
X513968Y265023D01*
G01X518454Y262800D02*
X514631Y266623D01*
G01X538408Y261200D02*
X517791D01*
G01X520015Y262800D02*
X518454D01*
G01X538408D02*
X523685D01*
G01X518409Y258851D02*
X517296D01*
G01X523351Y257251D02*
X517296D01*
G01X524014Y258851D02*
X522079D01*
G01X523351Y257251D02*
X517296D01*
G01X527025Y255840D02*
X524014Y258851D01*
G01X526362Y254240D02*
X523351Y257251D01*
G01X528074Y255840D02*
X527025D01*
G01X528128Y254240D02*
X526362D01*
G01X523351Y257251D02*
X517296D01*
G01X518409Y258851D02*
X517296D01*
G01X524014D02*
X522079D01*
G01X526362Y254240D02*
X523351Y257251D01*
G01X527025Y255840D02*
X524014Y258851D01*
G01X528128Y254240D02*
X526362D01*
G01X528074Y255840D02*
X527025D01*
G01X520827Y254506D02*
X517860D01*
G01X520164Y252906D02*
X517860D01*
G01X524655Y250678D02*
X520827Y254506D01*
G01X523992Y249078D02*
X520164Y252906D01*
G01X530760Y250678D02*
X524655D01*
G01X525462Y249078D02*
X523992D01*
G01X530097D02*
X529052D01*
G01X534120Y247318D02*
X530760Y250678D01*
G01X532520Y246655D02*
X530097Y249078D01*
G01X534120Y242457D02*
Y247318D01*
G01X532520Y243057D02*
Y246655D01*
G01X520164Y252906D02*
X517860D01*
G01X520827Y254506D02*
X517860D01*
G01X523992Y249078D02*
X520164Y252906D01*
G01X524655Y250678D02*
X520827Y254506D01*
G01X525462Y249078D02*
X523992D01*
G01X530760Y250678D02*
X524655D01*
G01X530097Y249078D02*
X529052D01*
G01X530760Y250678D02*
X524655D01*
G01X532520Y246655D02*
X530097Y249078D01*
G01X534120Y247318D02*
X530760Y250678D01*
G01X532520Y243057D02*
Y246655D01*
G01X534120Y242457D02*
Y247318D01*
G01X557056Y298432D02*
X567998Y305542D01*
G01X554550Y297900D02*
X557056Y298432D01*
G01X554381Y299500D02*
X556433Y299936D01*
G01X538992Y297900D02*
X554550D01*
G01X538992Y299500D02*
X554381D01*
G01X557056Y298432D02*
X567998Y305542D01*
G01X554381Y299500D02*
X556433Y299936D01*
G01X554550Y297900D02*
X557056Y298432D01*
G01X538992Y299500D02*
X554381D01*
G01X538992Y297900D02*
X554550D01*
G01X518942Y305832D02*
X516833Y303723D01*
G01X517342Y306495D02*
X516170Y305323D01*
G01X518942Y308865D02*
Y305832D01*
G01X517342Y309528D02*
Y306495D01*
G01X519981Y309904D02*
X518942Y308865D01*
G01X527032Y319218D02*
X517342Y309528D01*
G01X527695Y317618D02*
X522577Y312500D01*
G01X527032Y319218D02*
X517342Y309528D01*
G01X533390Y317618D02*
X527695D01*
G01X533626Y319218D02*
X527032D01*
G01X517342Y306495D02*
X516170Y305323D01*
G01X518942Y305832D02*
X516833Y303723D01*
G01X517342Y309528D02*
Y306495D01*
G01X518942Y308865D02*
Y305832D01*
G01X527032Y319218D02*
X517342Y309528D01*
G01X519981Y309904D02*
X518942Y308865D01*
G01X527695Y317618D02*
X522577Y312500D01*
G01X533626Y319218D02*
X527032D01*
G01X533390Y317618D02*
X527695D01*
G01X533195Y305513D02*
X530349D01*
G01X533421Y307113D02*
X529686D01*
G01X533421D02*
X529686D01*
G01X533195Y305513D02*
X530349D01*
G01X533315Y299607D02*
X528985D01*
G01X533315D02*
X528985D01*
G01X529029Y311617D02*
X533291D01*
G01X528366Y313217D02*
X533525D01*
G01X521415Y304003D02*
X529029Y311617D01*
G01X516941Y301792D02*
X528366Y313217D01*
G01X517604Y300192D02*
X518819Y301407D01*
G01X516941Y301792D02*
X528366Y313217D01*
G01D02*
X533525D01*
G01X529029Y311617D02*
X533291D01*
G01X516941Y301792D02*
X528366Y313217D01*
G01X521415Y304003D02*
X529029Y311617D01*
G01X517604Y300192D02*
X518819Y301407D01*
G01X573077Y359595D02*
X559018Y381247D01*
G01X576015Y345771D02*
X573077Y359595D01*
G01X572504Y321554D02*
X577651Y345771D01*
G01X572344Y328502D02*
X576015Y345771D01*
G01X571000Y322177D02*
X571598Y324991D01*
G01X565777Y311194D02*
X572504Y321554D01*
G01X564620Y312351D02*
X571000Y322177D01*
G01X557774Y305996D02*
X565777Y311194D01*
G01X557150Y307500D02*
X564620Y312351D01*
G01X554970Y305400D02*
X557774Y305996D01*
G01X554801Y307000D02*
X557150Y307500D01*
G01X539092Y305400D02*
X554970D01*
G01X539092Y307000D02*
X554801D01*
G01X573077Y359595D02*
X559018Y381247D01*
G01X576015Y345771D02*
X573077Y359595D01*
G01X572344Y328502D02*
X576015Y345771D01*
G01X572504Y321554D02*
X577651Y345771D01*
G01X571000Y322177D02*
X571598Y324991D01*
G01X572504Y321554D02*
X577651Y345771D01*
G01X564620Y312351D02*
X571000Y322177D01*
G01X565777Y311194D02*
X572504Y321554D01*
G01X557150Y307500D02*
X564620Y312351D01*
G01X557774Y305996D02*
X565777Y311194D01*
G01X554801Y307000D02*
X557150Y307500D01*
G01X554970Y305400D02*
X557774Y305996D01*
G01X539092Y307000D02*
X554801D01*
G01X539092Y305400D02*
X554970D01*
G01X566841Y306699D02*
X577472Y323067D01*
G01X567998Y305542D02*
X573499Y314011D01*
G01X566841Y306699D02*
X577472Y323067D01*
G01X556433Y299936D02*
X566841Y306699D01*
G01D02*
X577472Y323067D01*
G01X567998Y305542D02*
X573499Y314011D01*
G01X556433Y299936D02*
X566841Y306699D01*
G01X563357Y359401D02*
X552801Y375653D01*
G01X561853Y358778D02*
X551644Y374496D01*
G01X565824Y347791D02*
X563359Y359401D01*
G01X564188Y347791D02*
X561856Y358774D01*
G01X560883Y324554D02*
X565824Y347791D01*
G01X560639Y331106D02*
X564188Y347791D01*
G01X559378Y325175D02*
X559892Y327594D01*
G01X557959Y320053D02*
X560883Y324554D01*
G01X556802Y321210D02*
X559378Y325175D01*
G01X555106Y318199D02*
X557959Y320053D01*
G01X554483Y319703D02*
X556802Y321210D01*
G01X551814Y317500D02*
X555106Y318199D01*
G01X551645Y319100D02*
X554483Y319703D01*
G01X539292Y317500D02*
X551814D01*
G01X539292Y319100D02*
X551645D01*
G01X561853Y358778D02*
X551644Y374496D01*
G01X563357Y359401D02*
X552801Y375653D01*
G01X564188Y347791D02*
X561856Y358774D01*
G01X565824Y347791D02*
X563359Y359401D01*
G01X560639Y331106D02*
X564188Y347791D01*
G01X560883Y324554D02*
X565824Y347791D01*
G01X559378Y325175D02*
X559892Y327594D01*
G01X560883Y324554D02*
X565824Y347791D01*
G01X556802Y321210D02*
X559378Y325175D01*
G01X557959Y320053D02*
X560883Y324554D01*
G01X554483Y319703D02*
X556802Y321210D01*
G01X555106Y318199D02*
X557959Y320053D01*
G01X551645Y319100D02*
X554483Y319703D01*
G01X551814Y317500D02*
X555106Y318199D01*
G01X539292Y319100D02*
X551645D01*
G01X539292Y317500D02*
X551814D01*
G01X568458Y360568D02*
X556450Y379055D01*
G01X566954Y359945D02*
X555293Y377898D01*
G01X571493Y346279D02*
X568458Y360568D01*
G01X569857Y346279D02*
X566954Y359945D01*
G01X566580Y323147D02*
X571493Y346279D01*
G01X568099Y338003D02*
X569857Y346279D01*
G01X565076Y323770D02*
X567353Y334491D01*
G01X563390Y318236D02*
X566580Y323147D01*
G01X562140Y319249D02*
X565074Y323766D01*
G01X557317Y312162D02*
X563390Y318236D01*
G01X556520Y313629D02*
X562140Y319249D01*
G01X554207Y311500D02*
X557317Y312162D01*
G01X554038Y313100D02*
X556520Y313629D01*
G01X539192Y311500D02*
X554207D01*
G01X539192Y313100D02*
X554038D01*
G01X566954Y359945D02*
X555293Y377898D01*
G01X568458Y360568D02*
X556450Y379055D01*
G01X569857Y346279D02*
X566954Y359945D01*
G01X571493Y346279D02*
X568458Y360568D01*
G01X568099Y338003D02*
X569857Y346279D01*
G01X566580Y323147D02*
X571493Y346279D01*
G01X565076Y323770D02*
X567353Y334491D01*
G01X566580Y323147D02*
X571493Y346279D01*
G01X562140Y319249D02*
X565074Y323766D01*
G01X563390Y318236D02*
X566580Y323147D01*
G01X556520Y313629D02*
X562140Y319249D01*
G01X557317Y312162D02*
X563390Y318236D01*
G01X554038Y313100D02*
X556520Y313629D01*
G01X554207Y311500D02*
X557317Y312162D01*
G01X539192Y313100D02*
X554038D01*
G01X539192Y311500D02*
X554207D01*
G01X574581Y360218D02*
X560175Y382404D01*
G01X574581Y360218D02*
X560175Y382404D01*
G01X579161Y362089D02*
X563659Y385964D01*
G01X577657Y361466D02*
X562502Y384807D01*
G01X577657Y361466D02*
X562502Y384807D01*
G01X579161Y362089D02*
X563659Y385964D01*
G01X584789Y13792D02*
X586145D01*
G01X584789Y12192D02*
X586145D01*
G01X583871Y14710D02*
G03X584789Y13792I918J0D01*
G01X582271Y14710D02*
G03X584789Y12192I2518J0D01*
G01X583871Y54021D02*
Y14710D01*
G01X582271Y53853D02*
Y14710D01*
G01X584789Y12192D02*
X586145D01*
G01X584789Y13792D02*
X586145D01*
G01X582271Y14710D02*
G03X584789Y12192I2518J0D01*
G01X583871Y14710D02*
G03X584789Y13792I918J0D01*
G01X582271Y53853D02*
Y14710D01*
G01X583871Y54021D02*
Y14710D01*
G01X577703Y18517D02*
X579059D01*
G01X577703Y16917D02*
X579059D01*
G01X576785Y19435D02*
G03X577703Y18517I918J0D01*
G01X575185Y19435D02*
G03X577703Y16917I2518J0D01*
G01X576785Y50819D02*
Y19435D01*
G01X575185Y50650D02*
Y19435D01*
G01X577703Y16917D02*
X579059D01*
G01X577703Y18517D02*
X579059D01*
G01X575185Y19435D02*
G03X577703Y16917I2518J0D01*
G01X576785Y19435D02*
G03X577703Y18517I918J0D01*
G01X575185Y50650D02*
Y19435D01*
G01X576785Y50819D02*
Y19435D01*
G01X583166Y57342D02*
X583871Y54021D01*
G01X581662Y56719D02*
X582271Y53853D01*
G01X578915Y63888D02*
X583166Y57342D01*
G01X577411Y63265D02*
X581662Y56719D01*
G01D02*
X582271Y53853D01*
G01X583166Y57342D02*
X583871Y54021D01*
G01X577411Y63265D02*
X581662Y56719D01*
G01X578915Y63888D02*
X583166Y57342D01*
G01X574808Y182223D02*
X576085Y176220D01*
G01X573171Y182224D02*
X574449Y176220D01*
G01X581829Y215106D02*
X574808Y182223D01*
G01X580325Y215730D02*
X573171Y182224D01*
G01X584904Y219842D02*
X581829Y215106D01*
G01X583400Y220465D02*
X580325Y215730D01*
G01X589499Y241462D02*
X584904Y219842D01*
G01X587865Y241472D02*
X583400Y220465D01*
G01X573171Y182224D02*
X574449Y176220D01*
G01X574808Y182223D02*
X576085Y176220D01*
G01X580325Y215730D02*
X573171Y182224D01*
G01X581829Y215106D02*
X574808Y182223D01*
G01X583400Y220465D02*
X580325Y215730D01*
G01X584904Y219842D02*
X581829Y215106D01*
G01X587865Y241472D02*
X583400Y220465D01*
G01X589499Y241462D02*
X584904Y219842D01*
G01X580100Y221626D02*
X575588Y214678D01*
G01X578596Y222249D02*
X574084Y215300D01*
G01X584417Y241940D02*
X580100Y221626D01*
G01X582781Y241940D02*
X578596Y222249D01*
G01D02*
X574084Y215300D01*
G01X580100Y221626D02*
X575588Y214678D01*
G01X582781Y241940D02*
X578596Y222249D01*
G01X584417Y241940D02*
X580100Y221626D01*
G01X579210Y242274D02*
X575155Y223192D01*
G01X577574Y242274D02*
X573651Y223815D01*
G01X577574Y242274D02*
X573651Y223815D01*
G01X579210Y242274D02*
X575155Y223192D01*
G01X585045Y263742D02*
X589499Y241462D01*
G01X583536Y263128D02*
X587865Y241472D01*
G01X575071Y279106D02*
X585045Y263742D01*
G01X578724Y270539D02*
X583536Y263128D01*
G01X573913Y277949D02*
X578724Y270539D01*
G01X583536Y263128D02*
X587865Y241472D01*
G01X585045Y263742D02*
X589499Y241462D01*
G01X578724Y270539D02*
X583536Y263128D01*
G01X575071Y279106D02*
X585045Y263742D01*
G01X573913Y277949D02*
X578724Y270539D01*
G01X575071Y279106D02*
X585045Y263742D01*
G01X580108Y262205D02*
X584417Y241940D01*
G01X578604Y261582D02*
X582781Y241940D01*
G01X574381Y268084D02*
X578604Y261582D01*
G01D02*
X582781Y241940D01*
G01X580108Y262205D02*
X584417Y241940D01*
G01X574381Y268084D02*
X578604Y261582D01*
G01X575464Y259908D02*
X579210Y242274D01*
G01X573960Y259285D02*
X577574Y242274D01*
G01X573960Y259285D02*
X577574Y242274D01*
G01X575464Y259908D02*
X579210Y242274D01*
G01X577651Y345771D02*
X574581Y360218D01*
G01X577651Y345771D02*
X574581Y360218D01*
G01X583279Y342699D02*
X579161Y362089D01*
G01X581643Y342699D02*
X577657Y361466D01*
G01X578976Y322444D02*
X583279Y342699D01*
G01X580190Y335860D02*
X581643Y342699D01*
G01X577472Y323067D02*
X579444Y332349D01*
G01X573499Y314011D02*
X578976Y322444D01*
G01X581643Y342699D02*
X577657Y361466D01*
G01X583279Y342699D02*
X579161Y362089D01*
G01X580190Y335860D02*
X581643Y342699D01*
G01X578976Y322444D02*
X583279Y342699D01*
G01X577472Y323067D02*
X579444Y332349D01*
G01X578976Y322444D02*
X583279Y342699D01*
G01X573499Y314011D02*
X578976Y322444D01*
G54D13*
G01X687141Y50017D02*
X671902Y60297D01*
G01X686662Y48861D02*
X674725Y56914D01*
G01X687141Y50017D02*
X671902Y60297D01*
G01X704211Y45450D02*
X686662Y48861D01*
G01X704329Y46675D02*
X687141Y50017D01*
G01D02*
X671902Y60297D01*
G01X686662Y48861D02*
X674725Y56914D01*
G01X704329Y46675D02*
X687141Y50017D01*
G01X704211Y45450D02*
X686662Y48861D01*
G01X695967Y108680D02*
X701400Y103247D01*
G01X694742Y108172D02*
X696091Y106823D01*
G01X695967Y108680D02*
X701400Y103247D01*
G01X694742Y111734D02*
Y108172D01*
G01X695967Y111734D02*
Y108680D01*
G01D02*
X701400Y103247D01*
G01X694742Y108172D02*
X696091Y106823D01*
G01X695967Y111734D02*
Y108680D01*
G01X694742Y111734D02*
Y108172D01*
G01X694895Y102286D02*
X697554Y99627D01*
G01X698779Y100135D02*
X692832Y106082D01*
G01X694047Y102286D02*
X694895D01*
G01X698779Y100135D02*
X692832Y106082D01*
G01X691607Y105574D02*
X692827Y104354D01*
G01X698779Y100135D02*
X692832Y106082D01*
G01X691607Y109143D02*
Y105574D01*
G01X692832Y106082D02*
Y114301D01*
G01X691607Y113793D02*
Y112068D01*
G01X692832Y106082D02*
Y114301D01*
G01Y106082D02*
Y114301D01*
G01X691607Y109143D02*
Y105574D01*
G01Y113793D02*
Y112068D01*
G01X698779Y100135D02*
X692832Y106082D01*
G01X694895Y102286D02*
X697554Y99627D01*
G01X694047Y102286D02*
X694895D01*
G01X691607Y105574D02*
X692827Y104354D01*
G01X689889Y87269D02*
Y84923D01*
G01X691114Y101246D02*
Y84963D01*
G01X689889Y91919D02*
Y90194D01*
G01X691114Y101246D02*
Y84963D01*
G01X689889Y96569D02*
Y94844D01*
G01X691114Y101246D02*
Y84963D01*
G01X689889Y100738D02*
Y99494D01*
G01X691114Y101246D02*
Y84963D01*
G01X688732Y101895D02*
X689889Y100738D01*
G01X687340Y105020D02*
X691114Y101246D01*
G01X687884Y101895D02*
X688732D01*
G01X687340Y105020D02*
X691114Y101246D01*
G01X686115Y104512D02*
X686664Y103963D01*
G01X687340Y105020D02*
X691114Y101246D01*
G01X686115Y106583D02*
Y104512D01*
G01X687340Y111714D02*
Y105020D01*
G01X686115Y111206D02*
Y109508D01*
G01X687340Y111714D02*
Y105020D01*
G01X685179Y112142D02*
X686115Y111206D01*
G01X684098Y114956D02*
X687340Y111714D01*
G01X684330Y112142D02*
X685179D01*
G01X684098Y114956D02*
X687340Y111714D01*
G01X691114Y101246D02*
Y84963D01*
G01X689889Y87269D02*
Y84923D01*
G01Y91919D02*
Y90194D01*
G01Y96569D02*
Y94844D01*
G01Y100738D02*
Y99494D01*
G01X687340Y105020D02*
X691114Y101246D01*
G01X688732Y101895D02*
X689889Y100738D01*
G01X687884Y101895D02*
X688732D01*
G01X686115Y104512D02*
X686664Y103963D01*
G01X687340Y111714D02*
Y105020D01*
G01X686115Y106583D02*
Y104512D01*
G01Y111206D02*
Y109508D01*
G01X684098Y114956D02*
X687340Y111714D01*
G01X685179Y112142D02*
X686115Y111206D01*
G01X684330Y112142D02*
X685179D01*
G01X681908Y86576D02*
Y84476D01*
G01X683133Y110834D02*
Y84427D01*
G01X681908Y91326D02*
Y89601D01*
G01X683133Y110834D02*
Y84427D01*
G01X681908Y96076D02*
Y94351D01*
G01X683133Y110834D02*
Y84427D01*
G01X681908Y100826D02*
Y99101D01*
G01X683133Y110834D02*
Y84427D01*
G01X681908Y105576D02*
Y103851D01*
G01X683133Y110834D02*
Y84427D01*
G01X681908Y110326D02*
Y108601D01*
G01X683133Y110834D02*
Y84427D01*
G01X680095Y112139D02*
X681908Y110326D01*
G01X681320Y112647D02*
X683133Y110834D01*
G01X680095Y117000D02*
Y112139D01*
G01X681320Y117000D02*
Y112647D01*
G01X683133Y110834D02*
Y84427D01*
G01X681908Y86576D02*
Y84476D01*
G01Y91326D02*
Y89601D01*
G01Y96076D02*
Y94351D01*
G01Y100826D02*
Y99101D01*
G01Y105576D02*
Y103851D01*
G01Y110326D02*
Y108601D01*
G01X681320Y112647D02*
X683133Y110834D01*
G01X680095Y112139D02*
X681908Y110326D01*
G01X681320Y117000D02*
Y112647D01*
G01X680095Y117000D02*
Y112139D01*
G01X673727Y86319D02*
Y84692D01*
G01X674952Y114219D02*
Y84463D01*
G01X673727Y90969D02*
Y89244D01*
G01X674952Y114219D02*
Y84463D01*
G01X673727Y95619D02*
Y93894D01*
G01X674952Y114219D02*
Y84463D01*
G01X673727Y100269D02*
Y98544D01*
G01X674952Y114219D02*
Y84463D01*
G01X673727Y104919D02*
Y103194D01*
G01X674952Y114219D02*
Y84463D01*
G01X673727Y109569D02*
Y107844D01*
G01X674952Y114219D02*
Y84463D01*
G01X673727Y114219D02*
Y112752D01*
G01X674952Y114219D02*
Y84463D01*
G01Y114219D02*
Y84463D01*
G01X673727Y86319D02*
Y84692D01*
G01Y90969D02*
Y89244D01*
G01Y95619D02*
Y93894D01*
G01Y100269D02*
Y98544D01*
G01Y104919D02*
Y103194D01*
G01Y109569D02*
Y107844D01*
G01Y114219D02*
Y112752D01*
G01X665730Y86247D02*
Y84249D01*
G01X666955Y108989D02*
Y84389D01*
G01X665730Y90897D02*
Y89172D01*
G01X666955Y108989D02*
Y84389D01*
G01X665730Y95547D02*
Y93822D01*
G01X666955Y108989D02*
Y84389D01*
G01X665730Y100197D02*
Y98472D01*
G01X666955Y108989D02*
Y84389D01*
G01X665730Y104847D02*
Y103122D01*
G01X666955Y108989D02*
Y84389D01*
G01X665730Y109497D02*
Y107772D01*
G01X666955Y108989D02*
Y84389D01*
G01X666326Y110093D02*
X665730Y109497D01*
G01X670652Y112686D02*
X666955Y108989D01*
G01X668802Y112570D02*
X667546D01*
G01X670652Y112686D02*
X666955Y108989D01*
G01X668957Y112725D02*
X668802Y112570D01*
G01X670652Y112686D02*
X666955Y108989D01*
G01X669427Y113195D02*
X669018Y112786D01*
G01X670652Y112686D02*
X666955Y108989D01*
G01X669427Y114000D02*
Y113195D01*
G01X670652Y114000D02*
Y112686D01*
G01X666955Y108989D02*
Y84389D01*
G01X665730Y86247D02*
Y84249D01*
G01Y90897D02*
Y89172D01*
G01Y95547D02*
Y93822D01*
G01Y100197D02*
Y98472D01*
G01Y104847D02*
Y103122D01*
G01Y109497D02*
Y107772D01*
G01X670652Y112686D02*
X666955Y108989D01*
G01X666326Y110093D02*
X665730Y109497D01*
G01X668802Y112570D02*
X667546D01*
G01X668957Y112725D02*
X668802Y112570D01*
G01X669427Y113195D02*
X669018Y112786D01*
G01X670652Y114000D02*
Y112686D01*
G01X669427Y114000D02*
Y113195D01*
G01X656771Y85415D02*
Y83771D01*
G01X657996Y84907D02*
Y83604D01*
G01X657720Y86364D02*
X656771Y85415D01*
G01X658945Y85856D02*
X657996Y84907D01*
G01X657720Y87512D02*
Y86364D01*
G01X658945Y105410D02*
Y85856D01*
G01X657720Y92162D02*
Y90437D01*
G01X658945Y105410D02*
Y85856D01*
G01X657720Y96812D02*
Y95087D01*
G01X658945Y105410D02*
Y85856D01*
G01X657720Y101462D02*
Y99737D01*
G01X658945Y105410D02*
Y85856D01*
G01X657720Y105918D02*
Y104387D01*
G01X658945Y105410D02*
Y85856D01*
G01X658637Y106835D02*
X657720Y105918D01*
G01X662917Y109382D02*
X658945Y105410D01*
G01X660705Y108903D02*
X659857D01*
G01X662917Y109382D02*
X658945Y105410D01*
G01X662100Y110298D02*
X660705Y108903D01*
G01X662917Y109382D02*
X658945Y105410D01*
G01X657996Y84907D02*
Y83604D01*
G01X656771Y85415D02*
Y83771D01*
G01X658945Y85856D02*
X657996Y84907D01*
G01X657720Y86364D02*
X656771Y85415D01*
G01X658945Y105410D02*
Y85856D01*
G01X657720Y87512D02*
Y86364D01*
G01Y92162D02*
Y90437D01*
G01Y96812D02*
Y95087D01*
G01Y101462D02*
Y99737D01*
G01Y105918D02*
Y104387D01*
G01X662917Y109382D02*
X658945Y105410D01*
G01X658637Y106835D02*
X657720Y105918D01*
G01X660705Y108903D02*
X659857D01*
G01X662100Y110298D02*
X660705Y108903D01*
G01X659807Y112813D02*
X660108Y113114D01*
G01X660975Y112249D02*
X651102Y102376D01*
G01X658480Y111487D02*
X659806Y112813D01*
G01X660975Y112249D02*
X651102Y102376D01*
G01X655192Y108199D02*
X656412Y109419D01*
G01X660975Y112249D02*
X651102Y102376D01*
G01X649877Y102884D02*
X653124Y106131D01*
G01X660975Y112249D02*
X651102Y102376D01*
G01X649877Y101846D02*
Y102884D01*
G01X651102Y102376D02*
Y83532D01*
G01X649877Y97196D02*
Y98921D01*
G01X651102Y102376D02*
Y83532D01*
G01X649877Y92546D02*
Y94271D01*
G01X651102Y102376D02*
Y83532D01*
G01X649877Y87896D02*
Y89621D01*
G01X651102Y102376D02*
Y83532D01*
G01X649877Y83319D02*
Y84971D01*
G01X651102Y102376D02*
Y83532D01*
G01Y102376D02*
Y83532D01*
G01X649877Y101846D02*
Y102884D01*
G01Y97196D02*
Y98921D01*
G01Y92546D02*
Y94271D01*
G01Y87896D02*
Y89621D01*
G01Y83319D02*
Y84971D01*
G01X660975Y112249D02*
X651102Y102376D01*
G01X659807Y112813D02*
X660108Y113114D01*
G01X658480Y111487D02*
X659806Y112813D01*
G01X655192Y108199D02*
X656412Y109419D01*
G01X649877Y102884D02*
X653124Y106131D01*
G01X689601Y79766D02*
Y80946D01*
G01X690826Y80274D02*
Y80843D01*
G01X690696Y78671D02*
X689601Y79766D01*
G01X691306Y79794D02*
X690826Y80274D01*
G01X705857Y75449D02*
X690696Y78671D01*
G01X706112Y76648D02*
X691306Y79794D01*
G01X690826Y80274D02*
Y80843D01*
G01X689601Y79766D02*
Y80946D01*
G01X691306Y79794D02*
X690826Y80274D01*
G01X690696Y78671D02*
X689601Y79766D01*
G01X706112Y76648D02*
X691306Y79794D01*
G01X705857Y75449D02*
X690696Y78671D01*
G01X681775Y78233D02*
Y80637D01*
G01X683000Y78623D02*
Y80567D01*
G01X683698Y75512D02*
X681775Y78233D01*
G01X684422Y76611D02*
X683000Y78623D01*
G01X714519Y68961D02*
X683698Y75512D01*
G01X714996Y70113D02*
X684422Y76611D01*
G01X683000Y78623D02*
Y80567D01*
G01X681775Y78233D02*
Y80637D01*
G01X684422Y76611D02*
X683000Y78623D01*
G01X683698Y75512D02*
X681775Y78233D01*
G01X714996Y70113D02*
X684422Y76611D01*
G01X714519Y68961D02*
X683698Y75512D01*
G01X673547Y79457D02*
Y80509D01*
G01X674772Y79730D02*
Y80576D01*
G01X675333Y75646D02*
X673547Y79457D01*
G01X676299Y76473D02*
X674772Y79730D01*
G01X684395Y69536D02*
X675333Y75646D01*
G01X684874Y70691D02*
X676299Y76473D01*
G01X713270Y63922D02*
X684395Y69536D01*
G01X686567Y70363D02*
X684874Y70691D01*
G01X691132Y69475D02*
X689439Y69805D01*
G01X695696Y68588D02*
X694003Y68917D01*
G01X674772Y79730D02*
Y80576D01*
G01X673547Y79457D02*
Y80509D01*
G01X676299Y76473D02*
X674772Y79730D01*
G01X675333Y75646D02*
X673547Y79457D01*
G01X684874Y70691D02*
X676299Y76473D01*
G01X684395Y69536D02*
X675333Y75646D01*
G01X686567Y70363D02*
X684874Y70691D01*
G01X713270Y63922D02*
X684395Y69536D01*
G01X691132Y69475D02*
X689439Y69805D01*
G01X713270Y63922D02*
X684395Y69536D01*
G01X695696Y68588D02*
X694003Y68917D01*
G01X713270Y63922D02*
X684395Y69536D01*
G01X713270Y63922D02*
X684395Y69536D01*
G01X713270Y63922D02*
X684395Y69536D01*
G01X665838Y79292D02*
Y81051D01*
G01X667063Y79491D02*
Y81107D01*
G01X666882Y76155D02*
X665838Y79292D01*
G01X668045Y76542D02*
X667063Y79491D01*
G01X667333Y74800D02*
X666882Y76155D01*
G01X668369Y75567D02*
X668046Y76541D01*
G01X682474Y64036D02*
X667333Y74800D01*
G01X673565Y71873D02*
X668369Y75567D01*
G01X674401Y72014D02*
X673565Y71873D01*
G01X677355Y69179D02*
X675949Y70178D01*
G01X678191Y69320D02*
X677355Y69179D01*
G01X682968Y65188D02*
X679738Y67485D01*
G01X702419Y60159D02*
X682474Y64036D01*
G01X689226Y63972D02*
X682968Y65188D01*
G01X693790Y63084D02*
X692097Y63413D01*
G01X702419Y61407D02*
X696662Y62526D01*
G01X667063Y79491D02*
Y81107D01*
G01X665838Y79292D02*
Y81051D01*
G01X668045Y76542D02*
X667063Y79491D01*
G01X666882Y76155D02*
X665838Y79292D01*
G01X668369Y75567D02*
X668046Y76541D01*
G01X667333Y74800D02*
X666882Y76155D01*
G01X673565Y71873D02*
X668369Y75567D01*
G01X682474Y64036D02*
X667333Y74800D01*
G01X674401Y72014D02*
X673565Y71873D01*
G01X682474Y64036D02*
X667333Y74800D01*
G01X677355Y69179D02*
X675949Y70178D01*
G01X682474Y64036D02*
X667333Y74800D01*
G01X678191Y69320D02*
X677355Y69179D01*
G01X682474Y64036D02*
X667333Y74800D01*
G01X682968Y65188D02*
X679738Y67485D01*
G01X682474Y64036D02*
X667333Y74800D01*
G01X689226Y63972D02*
X682968Y65188D01*
G01X702419Y60159D02*
X682474Y64036D01*
G01X693790Y63084D02*
X692097Y63413D01*
G01X702419Y60159D02*
X682474Y64036D01*
G01X702419Y61407D02*
X696662Y62526D01*
G01X702419Y60159D02*
X682474Y64036D01*
G01X656550Y78474D02*
Y79426D01*
G01X657775Y78593D02*
Y79091D01*
G01X656885Y76753D02*
X656550Y78474D01*
G01X658040Y77232D02*
X657775Y78593D01*
G01X658761Y73975D02*
X656885Y76753D01*
G01X659641Y74861D02*
X658040Y77232D01*
G01X679831Y59768D02*
X658761Y73975D01*
G01X661469Y73627D02*
X659641Y74861D01*
G01X662302Y73789D02*
X661469Y73627D01*
G01X665325Y71027D02*
X663895Y71992D01*
G01X666158Y71190D02*
X665325Y71027D01*
G01X669181Y68428D02*
X667750Y69392D01*
G01X670014Y68590D02*
X669181Y68428D01*
G01X680310Y60924D02*
X671606Y66793D01*
G01X702627Y55342D02*
X679831Y59768D01*
G01X702627Y56590D02*
X680310Y60924D01*
G01X657775Y78593D02*
Y79091D01*
G01X656550Y78474D02*
Y79426D01*
G01X658040Y77232D02*
X657775Y78593D01*
G01X656885Y76753D02*
X656550Y78474D01*
G01X659641Y74861D02*
X658040Y77232D01*
G01X658761Y73975D02*
X656885Y76753D01*
G01X661469Y73627D02*
X659641Y74861D01*
G01X679831Y59768D02*
X658761Y73975D01*
G01X662302Y73789D02*
X661469Y73627D01*
G01X679831Y59768D02*
X658761Y73975D01*
G01X665325Y71027D02*
X663895Y71992D01*
G01X679831Y59768D02*
X658761Y73975D01*
G01X666158Y71190D02*
X665325Y71027D01*
G01X679831Y59768D02*
X658761Y73975D01*
G01X669181Y68428D02*
X667750Y69392D01*
G01X679831Y59768D02*
X658761Y73975D01*
G01X670014Y68590D02*
X669181Y68428D01*
G01X679831Y59768D02*
X658761Y73975D01*
G01X680310Y60924D02*
X671606Y66793D01*
G01X679831Y59768D02*
X658761Y73975D01*
G01X702627Y56590D02*
X680310Y60924D01*
G01X702627Y55342D02*
X679831Y59768D01*
G01X649888Y77436D02*
Y78832D01*
G01X651113Y77566D02*
Y78738D01*
G01X650103Y76431D02*
X649888Y77436D01*
G01X651254Y76909D02*
X651113Y77566D01*
G01X653462Y71259D02*
X650103Y76431D01*
G01X654354Y72135D02*
X651254Y76909D01*
G01X667723Y61637D02*
X653465Y71255D01*
G01X655249Y71531D02*
X654354Y72135D01*
G01X657912Y69734D02*
X655249Y71531D01*
G01X658745Y69895D02*
X657912Y69734D01*
G01X661767Y67133D02*
X660337Y68098D01*
G01X662600Y67295D02*
X661767Y67133D01*
G01X665622Y64533D02*
X664192Y65498D01*
G01X666455Y64695D02*
X665622Y64533D01*
G01X667722Y61637D02*
X667723D01*
G01X669477Y61933D02*
X668047Y62897D01*
G01X674724Y56914D02*
X667722Y61637D01*
G01X669477Y61933D02*
X668047Y62897D01*
G01X670310Y62094D02*
X669477Y61933D01*
G01X674725Y56914D02*
X674724D01*
G01X651113Y77566D02*
Y78738D01*
G01X649888Y77436D02*
Y78832D01*
G01X651254Y76909D02*
X651113Y77566D01*
G01X650103Y76431D02*
X649888Y77436D01*
G01X654354Y72135D02*
X651254Y76909D01*
G01X653462Y71259D02*
X650103Y76431D01*
G01X655249Y71531D02*
X654354Y72135D01*
G01X667723Y61637D02*
X653465Y71255D01*
G01X657912Y69734D02*
X655249Y71531D01*
G01X667723Y61637D02*
X653465Y71255D01*
G01X658745Y69895D02*
X657912Y69734D01*
G01X667723Y61637D02*
X653465Y71255D01*
G01X661767Y67133D02*
X660337Y68098D01*
G01X667723Y61637D02*
X653465Y71255D01*
G01X662600Y67295D02*
X661767Y67133D01*
G01X667723Y61637D02*
X653465Y71255D01*
G01X665622Y64533D02*
X664192Y65498D01*
G01X667723Y61637D02*
X653465Y71255D01*
G01X666455Y64695D02*
X665622Y64533D01*
G01X667723Y61637D02*
X653465Y71255D01*
G01X669477Y61933D02*
X668047Y62897D01*
G01X667722Y61637D02*
X667723D01*
G01X674724Y56914D02*
X667722Y61637D01*
G01X670310Y62094D02*
X669477Y61933D01*
G01X674724Y56914D02*
X667722Y61637D01*
G01X674725Y56914D02*
X674724D01*
G01X689401Y115999D02*
X691607Y113793D01*
G01X692832Y114301D02*
X690626Y116507D01*
G01X689401Y117632D02*
Y115999D01*
G01X690626Y116507D02*
Y117632D01*
G01Y116507D02*
Y117632D01*
G01X689401D02*
Y115999D01*
G01X692832Y114301D02*
X690626Y116507D01*
G01X689401Y115999D02*
X691607Y113793D01*
G01X682873Y116000D02*
Y114448D01*
G01X684098Y116000D02*
Y114956D01*
G01Y116000D02*
Y114956D01*
G01X682873Y116000D02*
Y114448D01*
G01X754111Y43015D02*
Y54419D01*
G01X755336Y43015D02*
Y54548D01*
G01X756400Y40726D02*
G02X754111Y43015I0J2289D01*
G01X756400Y41951D02*
G02X755336Y43015I0J1064D01*
G01X757574Y40726D02*
X756400D01*
G01X757573Y41951D02*
X756400D01*
G01X755336Y43015D02*
Y54548D01*
G01X754111Y43015D02*
Y54419D01*
G01X756400Y41951D02*
G02X755336Y43015I0J1064D01*
G01X756400Y40726D02*
G02X754111Y43015I0J2289D01*
G01X757573Y41951D02*
X756400D01*
G01X757574Y40726D02*
X756400D01*
G01X747025Y47739D02*
Y54193D01*
G01X748250Y47739D02*
Y54322D01*
G01X749314Y45450D02*
G02X747025Y47739I0J2289D01*
G01X749314Y46675D02*
G02X748250Y47739I0J1064D01*
G01X750488Y45450D02*
X749314D01*
G01X750487Y46675D02*
X749314D01*
G01X748250Y47739D02*
Y54322D01*
G01X747025Y47739D02*
Y54193D01*
G01X749314Y46675D02*
G02X748250Y47739I0J1064D01*
G01X749314Y45450D02*
G02X747025Y47739I0J2289D01*
G01X750487Y46675D02*
X749314D01*
G01X750488Y45450D02*
X749314D01*
G01X739938Y43015D02*
Y51852D01*
G01X741163Y43015D02*
Y51981D01*
G01X742227Y40726D02*
G02X739938Y43015I0J2289D01*
G01X742227Y41951D02*
G02X741163Y43015I0J1064D01*
G01X743401Y40726D02*
X742227D01*
G01X743400Y41951D02*
X742227D01*
G01X741163Y43015D02*
Y51981D01*
G01X739938Y43015D02*
Y51852D01*
G01X742227Y41951D02*
G02X741163Y43015I0J1064D01*
G01X742227Y40726D02*
G02X739938Y43015I0J2289D01*
G01X743400Y41951D02*
X742227D01*
G01X743401Y40726D02*
X742227D01*
G01X732851Y47739D02*
Y54154D01*
G01X734076Y47739D02*
Y54518D01*
G01X735140Y45450D02*
G02X732851Y47739I0J2289D01*
G01X735140Y46675D02*
G02X734076Y47739I0J1064D01*
G01X736314Y45450D02*
X735140D01*
G01X736313Y46675D02*
X735140D01*
G01X734076Y47739D02*
Y54518D01*
G01X732851Y47739D02*
Y54154D01*
G01X735140Y46675D02*
G02X734076Y47739I0J1064D01*
G01X735140Y45450D02*
G02X732851Y47739I0J2289D01*
G01X736313Y46675D02*
X735140D01*
G01X736314Y45450D02*
X735140D01*
G01X725765Y43015D02*
Y52401D01*
G01X726990Y43015D02*
Y52520D01*
G01X728054Y40726D02*
G02X725765Y43015I0J2289D01*
G01X728054Y41951D02*
G02X726990Y43015I0J1064D01*
G01X729228Y40726D02*
X728054D01*
G01X729227Y41951D02*
X728054D01*
G01X726990Y43015D02*
Y52520D01*
G01X725765Y43015D02*
Y52401D01*
G01X728054Y41951D02*
G02X726990Y43015I0J1064D01*
G01X728054Y40726D02*
G02X725765Y43015I0J2289D01*
G01X729227Y41951D02*
X728054D01*
G01X729228Y40726D02*
X728054D01*
G01X718679Y49870D02*
X718057Y52797D01*
G01X719905Y49999D02*
X719208Y53274D01*
G01X718679Y47738D02*
Y49869D01*
G01X719904Y47738D02*
Y49999D01*
G01X720967Y45450D02*
G02X718679Y47738I0J2288D01*
G01X720967Y46675D02*
G02X719904Y47738I0J1063D01*
G01X722141Y45450D02*
X720967D01*
G01X722140Y46675D02*
X720967D01*
G01X719905Y49999D02*
X719208Y53274D01*
G01X718679Y49870D02*
X718057Y52797D01*
G01X719904Y47738D02*
Y49999D01*
G01X718679Y47738D02*
Y49869D01*
G01X720967Y46675D02*
G02X719904Y47738I0J1063D01*
G01X720967Y45450D02*
G02X718679Y47738I0J2288D01*
G01X722140Y46675D02*
X720967D01*
G01X722141Y45450D02*
X720967D01*
G01X711592Y43015D02*
Y52354D01*
G01X712817Y43015D02*
Y52484D01*
G01X713881Y40726D02*
G02X711592Y43015I0J2289D01*
G01X713881Y41951D02*
G02X712817Y43015I0J1064D01*
G01X715055Y40726D02*
X713881D01*
G01X715054Y41951D02*
X713881D01*
G01X712817Y43015D02*
Y52484D01*
G01X711592Y43015D02*
Y52354D01*
G01X713881Y41951D02*
G02X712817Y43015I0J1064D01*
G01X713881Y40726D02*
G02X711592Y43015I0J2289D01*
G01X715054Y41951D02*
X713881D01*
G01X715055Y40726D02*
X713881D01*
G01X707968Y45450D02*
X704211D01*
G01X707967Y46675D02*
X704329D01*
G01X707967D02*
X704329D01*
G01X707968Y45450D02*
X704211D01*
G01X718121Y84280D02*
X715753D01*
G01X718240Y85505D02*
X715899D01*
G01X724927Y82955D02*
X718121Y84280D01*
G01X725406Y84110D02*
X718240Y85505D01*
G01X746334Y68516D02*
X724927Y82955D01*
G01X747226Y69393D02*
X725406Y84110D01*
G01X753439Y57580D02*
X746334Y68516D01*
G01X754590Y58057D02*
X747226Y69393D01*
G01X754111Y54419D02*
X753439Y57580D01*
G01X755336Y54548D02*
X754590Y58057D01*
G01X718240Y85505D02*
X715899D01*
G01X718121Y84280D02*
X715753D01*
G01X725406Y84110D02*
X718240Y85505D01*
G01X724927Y82955D02*
X718121Y84280D01*
G01X747226Y69393D02*
X725406Y84110D01*
G01X746334Y68516D02*
X724927Y82955D01*
G01X754590Y58057D02*
X747226Y69393D01*
G01X753439Y57580D02*
X746334Y68516D01*
G01X755336Y54548D02*
X754590Y58057D01*
G01X754111Y54419D02*
X753439Y57580D01*
G01X704360Y81469D02*
X703987D01*
G01X712713Y80028D02*
X704762Y82628D01*
G01X712404Y78840D02*
X704360Y81469D01*
G01X712713Y80028D02*
X704762Y82628D01*
G01X716226Y78096D02*
X712404Y78840D01*
G01X716490Y79293D02*
X712713Y80028D01*
G01X721261Y76851D02*
X716226Y78096D01*
G01X726792Y76746D02*
X716490Y79293D01*
G01X726298Y75606D02*
X721261Y76851D01*
G01X726792Y76746D02*
X716490Y79293D01*
G01X734649Y70183D02*
X726298Y75606D01*
G01X739435Y68537D02*
X726792Y76746D01*
G01X738549Y67651D02*
X737102Y68590D01*
G01X739435Y68537D02*
X726792Y76746D01*
G01X746898Y54791D02*
X738549Y67651D01*
G01X748049Y55268D02*
X739435Y68537D01*
G01X747025Y54193D02*
X746898Y54791D01*
G01X748250Y54322D02*
X748049Y55268D01*
G01X712713Y80028D02*
X704762Y82628D01*
G01X704360Y81469D02*
X703987D01*
G01X712404Y78840D02*
X704360Y81469D01*
G01X716490Y79293D02*
X712713Y80028D01*
G01X716226Y78096D02*
X712404Y78840D01*
G01X726792Y76746D02*
X716490Y79293D01*
G01X721261Y76851D02*
X716226Y78096D01*
G01X726298Y75606D02*
X721261Y76851D01*
G01X739435Y68537D02*
X726792Y76746D01*
G01X734649Y70183D02*
X726298Y75606D01*
G01X738549Y67651D02*
X737102Y68590D01*
G01X748049Y55268D02*
X739435Y68537D01*
G01X746898Y54791D02*
X738549Y67651D01*
G01X748250Y54322D02*
X748049Y55268D01*
G01X747025Y54193D02*
X746898Y54791D01*
G01X710714Y84166D02*
X711572D01*
G01X710963Y85391D02*
X711465D01*
G01X707248Y85630D02*
X710714Y84166D01*
G01X710963Y85391D02*
X711465D01*
G01X707946Y86666D02*
X710963Y85391D01*
G01X706574Y86304D02*
X707248Y85630D01*
G01X707442Y87170D02*
X707946Y86666D01*
G01X707299Y87313D02*
X707442Y87169D01*
G01X706074Y86805D02*
X706574Y86304D01*
G01X707442Y87170D02*
X707946Y86666D01*
G01X707299Y87313D02*
X707442Y87169D01*
G01X706074Y90952D02*
Y86805D01*
G01X707299Y100760D02*
Y87313D01*
G01X706074Y95602D02*
Y93877D01*
G01X707299Y100760D02*
Y87313D01*
G01X706074Y100252D02*
Y98527D01*
G01X707299Y100760D02*
Y87313D01*
G01X704304Y102022D02*
X706074Y100252D01*
G01X704812Y103247D02*
X707299Y100760D01*
G01X700892Y102022D02*
X704304D01*
G01X701400Y103247D02*
X704812D01*
G01X698159Y104755D02*
X700892Y102022D01*
G01X710963Y85391D02*
X711465D01*
G01X710714Y84166D02*
X711572D01*
G01X707248Y85630D02*
X710714Y84166D01*
G01X707946Y86666D02*
X710963Y85391D01*
G01X707248Y85630D02*
X710714Y84166D01*
G01X707442Y87170D02*
X707946Y86666D01*
G01X706574Y86304D02*
X707248Y85630D01*
G01X706074Y86805D02*
X706574Y86304D01*
G01X707299Y87313D02*
X707442Y87169D01*
G01X706574Y86304D02*
X707248Y85630D01*
G01X706074Y86805D02*
X706574Y86304D01*
G01X707299Y100760D02*
Y87313D01*
G01X706074Y90952D02*
Y86805D01*
G01Y95602D02*
Y93877D01*
G01Y100252D02*
Y98527D01*
G01X704812Y103247D02*
X707299Y100760D01*
G01X704304Y102022D02*
X706074Y100252D01*
G01X701400Y103247D02*
X704812D01*
G01X700892Y102022D02*
X704304D01*
G01X698159Y104755D02*
X700892Y102022D01*
G01X698953Y81562D02*
X700802D01*
G01X700442Y82787D02*
X699452D01*
G01X697554Y82927D02*
X698953Y81562D01*
G01X699452Y82787D02*
X698779Y83444D01*
G01X700442Y82787D02*
X699452D01*
G01X697554Y99627D02*
Y82927D01*
G01X698779Y83444D02*
Y100135D01*
G01Y83444D02*
Y100135D01*
G01X697554Y99627D02*
Y82927D01*
G01X699452Y82787D02*
X698779Y83444D01*
G01X697554Y82927D02*
X698953Y81562D01*
G01X700442Y82787D02*
X699452D01*
G01X698953Y81562D02*
X700802D01*
G01X697554Y82927D02*
X698953Y81562D01*
G01X713150Y73899D02*
X705857Y75449D01*
G01X720918Y73501D02*
X706112Y76648D01*
G01X720441Y72350D02*
X713150Y73899D01*
G01X720918Y73501D02*
X706112Y76648D01*
G01X733142Y64101D02*
X720441Y72350D01*
G01X726239Y70046D02*
X720918Y73501D01*
G01X730139Y67513D02*
X728692Y68453D01*
G01X734028Y64987D02*
X732592Y65920D01*
G01X739375Y54502D02*
X733142Y64101D01*
G01X734967Y63540D02*
X734028Y64987D01*
G01X740527Y54979D02*
X736561Y61087D01*
G01X739938Y51852D02*
X739375Y54502D01*
G01X741163Y51981D02*
X740527Y54979D01*
G01X720918Y73501D02*
X706112Y76648D01*
G01X713150Y73899D02*
X705857Y75449D01*
G01X720441Y72350D02*
X713150Y73899D01*
G01X726239Y70046D02*
X720918Y73501D01*
G01X733142Y64101D02*
X720441Y72350D01*
G01X730139Y67513D02*
X728692Y68453D01*
G01X733142Y64101D02*
X720441Y72350D01*
G01X734028Y64987D02*
X732592Y65920D01*
G01X733142Y64101D02*
X720441Y72350D01*
G01X734967Y63540D02*
X734028Y64987D01*
G01X739375Y54502D02*
X733142Y64101D01*
G01X740527Y54979D02*
X736561Y61087D01*
G01X739375Y54502D02*
X733142Y64101D01*
G01X741163Y51981D02*
X740527Y54979D01*
G01X739938Y51852D02*
X739375Y54502D01*
G01X714900Y68714D02*
X714519Y68961D01*
G01X716443Y69174D02*
X714996Y70113D01*
G01X729587Y59177D02*
X714900Y68714D01*
G01X716443Y69174D02*
X714996Y70113D01*
G01X720343Y66642D02*
X718896Y67581D01*
G01X724243Y64109D02*
X722796Y65048D01*
G01X730473Y60063D02*
X726696Y62516D01*
G01X732851Y54154D02*
X729587Y59177D01*
G01X734076Y54518D02*
X730473Y60063D01*
G01X716443Y69174D02*
X714996Y70113D01*
G01X714900Y68714D02*
X714519Y68961D01*
G01X729587Y59177D02*
X714900Y68714D01*
G01X720343Y66642D02*
X718896Y67581D01*
G01X729587Y59177D02*
X714900Y68714D01*
G01X724243Y64109D02*
X722796Y65048D01*
G01X729587Y59177D02*
X714900Y68714D01*
G01X730473Y60063D02*
X726696Y62516D01*
G01X729587Y59177D02*
X714900Y68714D01*
G01X734076Y54518D02*
X730473Y60063D01*
G01X732851Y54154D02*
X729587Y59177D01*
G01X700261Y67701D02*
X698568Y68030D01*
G01X713749Y65078D02*
X703132Y67142D01*
G01X723965Y56708D02*
X713270Y63922D01*
G01X724848Y57590D02*
X713749Y65078D01*
G01X725315Y54703D02*
X723965Y56708D01*
G01X726471Y55182D02*
X724848Y57590D01*
G01X725765Y52401D02*
X725315Y54703D01*
G01X726990Y52520D02*
X726471Y55182D01*
G01X700261Y67701D02*
X698568Y68030D01*
G01X713749Y65078D02*
X703132Y67142D01*
G01X724848Y57590D02*
X713749Y65078D01*
G01X723965Y56708D02*
X713270Y63922D01*
G01X726471Y55182D02*
X724848Y57590D01*
G01X725315Y54703D02*
X723965Y56708D01*
G01X726990Y52520D02*
X726471Y55182D01*
G01X725765Y52401D02*
X725315Y54703D01*
G01X705726Y60801D02*
X702419Y60159D01*
G01X705726Y62049D02*
X702419Y61407D01*
G01X711280Y59721D02*
X705726Y60801D01*
G01X711748Y60879D02*
X705726Y62049D01*
G01X715224Y57160D02*
X711280Y59721D01*
G01X716110Y58046D02*
X711748Y60879D01*
G01X718057Y52797D02*
X715224Y57160D01*
G01X719209Y53274D02*
X716110Y58046D01*
G01X705726Y62049D02*
X702419Y61407D01*
G01X705726Y60801D02*
X702419Y60159D01*
G01X711748Y60879D02*
X705726Y62049D01*
G01X711280Y59721D02*
X705726Y60801D01*
G01X716110Y58046D02*
X711748Y60879D01*
G01X715224Y57160D02*
X711280Y59721D01*
G01X719209Y53274D02*
X716110Y58046D01*
G01X718057Y52797D02*
X715224Y57160D01*
G01X706353Y56064D02*
X702627Y55342D01*
G01X706374Y57316D02*
X702627Y56590D01*
G01X709428Y55359D02*
X706353Y56064D01*
G01X709866Y56516D02*
X706374Y57316D01*
G01X710466Y54794D02*
X709428Y55359D01*
G01X711325Y55722D02*
X709866Y56516D01*
G01X711367Y53406D02*
X710466Y54794D01*
G01X712518Y53883D02*
X711325Y55722D01*
G01X711592Y52354D02*
X711367Y53406D01*
G01X712817Y52484D02*
X712518Y53883D01*
G01X706374Y57316D02*
X702627Y56590D01*
G01X706353Y56064D02*
X702627Y55342D01*
G01X709866Y56516D02*
X706374Y57316D01*
G01X709428Y55359D02*
X706353Y56064D01*
G01X711325Y55722D02*
X709866Y56516D01*
G01X710466Y54794D02*
X709428Y55359D01*
G01X712518Y53883D02*
X711325Y55722D01*
G01X711367Y53406D02*
X710466Y54794D01*
G01X712817Y52484D02*
X712518Y53883D01*
G01X711592Y52354D02*
X711367Y53406D01*
M02*
